FILE_TYPE = MACRO_DRAWING;
SET COLOR_WIRE YELLOW;
SET COLOR_PROP MONO;
SET COLOR_DOT WHITE;
SET COLOR_ARC YELLOW;
SET COLOR_BODY GREEN;
SET COLOR_NOTE MONO;
SET PROP_DISPLAY VALUE;
SET PAGE_NUMBER P207;
FORCEADD OFFPAGE..2
(-1800 4725);
FORCEPROP 2 LAST $XR0 206 
J 0
(-1611 4725);
DISPLAY 0.638298 (-1611 4725);
PAINT MONO (-1611 4725);
FORCEPROP 2 LAST ROOM PVCCIN_CPU1_PWR_VR
J 0
(-2200 4800);
DISPLAY 1.936170 (-2200 4800);
PAINT ORANGE (-2200 4800);
DISPLAY INVISIBLE (-2200 4800);
FORCEPROP 2 LAST CDS_LIB mstr_standard
J 2
(-1800 4725);
DISPLAY 1.936170 (-1800 4725);
PAINT ORANGE (-1800 4725);
DISPLAY INVISIBLE (-1800 4725);
FORCEPROP 2 LAST PATH I1
J 0
(-1595 4775);
DISPLAY 1.021277 (-1595 4775);
PAINT ORANGE (-1595 4775);
DISPLAY INVISIBLE (-1595 4775);
FORCEPROP 2 LAST BOM_COST PROC_VRD_VCCIN_CPU0
J 0
(-1600 4775);
DISPLAY 1.446809 (-1600 4775);
PAINT MONO (-1600 4775);
DISPLAY INVISIBLE (-1600 4775);
FORCEPROP 1 LAST OFFPAGE TRUE
J 0
(-1475 4600);
DISPLAY 1.723404 (-1475 4600);
PAINT GREEN (-1475 4600);
DISPLAY INVISIBLE (-1475 4600);
FORCEPROP 1 LAST COMMENT_BODY TRUE
J 0
(-1845 4630);
DISPLAY 1.723404 (-1845 4630);
PAINT GREEN (-1845 4630);
DISPLAY INVISIBLE (-1845 4630);
FORCEADD INDUCTOR..1
(-2000 3525);
FORCEPROP 1 LAST MATERIAL IND
J 0
(-1960 3415);
DISPLAY 0.617021 (-1960 3415);
PAINT SKYBLUE (-1960 3415);
FORCEPROP 1 LAST PART_NUMBER D92183-034
J 0
(-2125 3475);
DISPLAY 0.617021 (-2125 3475);
PAINT BLUE (-2125 3475);
FORCEPROP 1 LASTPIN (-1900 3525) $PN 2
J 2
(-1890 3535);
DISPLAY 0.617021 (-1890 3535);
PAINT WHITE (-1890 3535);
FORCEPROP 1 LAST VALUE 0.12UH
J 2
(-2005 3415);
DISPLAY 0.617021 (-2005 3415);
PAINT SKYBLUE (-2005 3415);
FORCEPROP 1 LAST LOCATION L1E1
J 0
(-2100 3575);
DISPLAY 0.617021 (-2100 3575);
PAINT AQUA (-2100 3575);
FORCEPROP 1 LASTPIN (-2100 3525) $PN 1
J 0
(-2100 3535);
DISPLAY 0.617021 (-2100 3535);
PAINT WHITE (-2100 3535);
FORCEPROP 1 LAST PACK_TYPE SM
J 0
(-1835 3415);
DISPLAY 0.617021 (-1835 3415);
PAINT SKYBLUE (-1835 3415);
FORCEPROP 2 LAST ROOM PVCCIN_CPU1_PWR_VR
J 0
(-2100 3625);
DISPLAY 1.361702 (-2100 3625);
PAINT ORANGE (-2100 3625);
DISPLAY INVISIBLE (-2100 3625);
FORCEPROP 1 LAST PATH I10
J 0
(-2100 3675);
DISPLAY 0.978723 (-2100 3675);
PAINT ORANGE (-2100 3675);
DISPLAY INVISIBLE (-2100 3675);
FORCEPROP 2 LAST CDS_LOCATION L1E1
J 0
(-2100 3575);
DISPLAY 0.617021 (-2100 3575);
PAINT AQUA (-2100 3575);
DISPLAY INVISIBLE (-2100 3575);
FORCEPROP 2 LAST $SEC 1
J 0
(-2100 3725);
PAINT MONO (-2100 3725);
DISPLAY INVISIBLE (-2100 3725);
FORCEPROP 2 LAST CDS_SEC 1
J 0
(-2100 3725);
PAINT MONO (-2100 3725);
DISPLAY INVISIBLE (-2100 3725);
FORCEPROP 2 LAST CDS_LIB mstr_discrete
J 0
(-2000 3525);
PAINT ORANGE (-2000 3525);
DISPLAY INVISIBLE (-2000 3525);
FORCEADD OFFPAGE..2
(-1300 2250);
FORCEPROP 2 LAST $XR0 206 
J 0
(-1111 2250);
DISPLAY 0.638298 (-1111 2250);
PAINT MONO (-1111 2250);
FORCEPROP 2 LAST ROOM PVCCIN_CPU1_PWR_VR
J 0
(-1700 2325);
DISPLAY 1.936170 (-1700 2325);
PAINT ORANGE (-1700 2325);
DISPLAY INVISIBLE (-1700 2325);
FORCEPROP 2 LAST CDS_LIB mstr_standard
J 0
(-1300 2250);
PAINT ORANGE (-1300 2250);
DISPLAY INVISIBLE (-1300 2250);
FORCEPROP 2 LAST PATH I11
J 0
(-1095 2300);
DISPLAY 1.021277 (-1095 2300);
PAINT ORANGE (-1095 2300);
DISPLAY INVISIBLE (-1095 2300);
FORCEPROP 2 LAST BOM_COST PROC_VRD_VCCIN_CPU0
J 0
(-1100 2300);
DISPLAY 1.446809 (-1100 2300);
PAINT MONO (-1100 2300);
DISPLAY INVISIBLE (-1100 2300);
FORCEPROP 1 LAST OFFPAGE TRUE
J 0
(-975 2125);
DISPLAY 1.723404 (-975 2125);
PAINT GREEN (-975 2125);
DISPLAY INVISIBLE (-975 2125);
FORCEPROP 1 LAST COMMENT_BODY TRUE
J 0
(-1345 2155);
DISPLAY 1.723404 (-1345 2155);
PAINT GREEN (-1345 2155);
DISPLAY INVISIBLE (-1345 2155);
FORCEADD OFFPAGE..2
(-1825 1475);
FORCEPROP 2 LAST $XR0 207 
J 0
(-1636 1475);
DISPLAY 0.638298 (-1636 1475);
PAINT MONO (-1636 1475);
FORCEPROP 2 LAST $XR1 208 
J 0
(-1516 1475);
DISPLAY 0.638298 (-1516 1475);
PAINT MONO (-1516 1475);
FORCEPROP 2 LAST $XR2 209 
J 0
(-1396 1475);
DISPLAY 0.638298 (-1396 1475);
PAINT MONO (-1396 1475);
FORCEPROP 2 LAST $XR3 206 
J 0
(-1276 1475);
DISPLAY 0.638298 (-1276 1475);
PAINT MONO (-1276 1475);
FORCEPROP 2 LAST ROOM PVCCIN_CPU1_PWR_VR
J 0
(-2225 1550);
DISPLAY 1.936170 (-2225 1550);
PAINT ORANGE (-2225 1550);
DISPLAY INVISIBLE (-2225 1550);
FORCEPROP 2 LAST CDS_LIB mstr_standard
J 0
(-1825 1475);
PAINT ORANGE (-1825 1475);
DISPLAY INVISIBLE (-1825 1475);
FORCEPROP 2 LAST BOM_COST PROC_VRD_VCCIN_CPU0
J 0
(-1625 1525);
DISPLAY 1.446809 (-1625 1525);
PAINT MONO (-1625 1525);
DISPLAY INVISIBLE (-1625 1525);
FORCEPROP 2 LAST PATH I13
J 0
(-1395 1525);
DISPLAY 1.021277 (-1395 1525);
PAINT ORANGE (-1395 1525);
DISPLAY INVISIBLE (-1395 1525);
FORCEPROP 1 LAST OFFPAGE TRUE
J 0
(-1500 1350);
DISPLAY 1.723404 (-1500 1350);
PAINT GREEN (-1500 1350);
DISPLAY INVISIBLE (-1500 1350);
FORCEPROP 1 LAST COMMENT_BODY TRUE
J 0
(-1870 1380);
DISPLAY 1.723404 (-1870 1380);
PAINT GREEN (-1870 1380);
DISPLAY INVISIBLE (-1870 1380);
FORCEADD PVCCIN_CPU1..1
(-1075 1025);
FORCEPROP 3 LASTPIN (-1075 975) SIG_NAME PVCCIN_CPU1\g
J 0
(-1065 985);
DISPLAY 0.659574 (-1065 985);
PAINT MONO (-1065 985);
DISPLAY INVISIBLE (-1065 985);
FORCEPROP 1 LAST VOLTAGE 2.0V
J 0
(-1120 982);
DISPLAY 0.340426 (-1120 982);
PAINT SKYBLUE (-1120 982);
DISPLAY INVISIBLE (-1120 982);
FORCEPROP 1 LAST PATH I14
J 0
(-1025 1050);
DISPLAY 0.872340 (-1025 1050);
PAINT AQUA (-1025 1050);
DISPLAY INVISIBLE (-1025 1050);
FORCEPROP 2 LAST CDS_LIB mstr_symbols
J 0
(-1075 1025);
PAINT ORANGE (-1075 1025);
DISPLAY INVISIBLE (-1075 1025);
FORCEPROP 1 LAST BODY_TYPE PLUMBING
J 0
(-1120 982);
DISPLAY 0.340426 (-1120 982);
PAINT GREEN (-1120 982);
DISPLAY INVISIBLE (-1120 982);
FORCEPROP 1 LAST HDL_POWER PVCCIN_CPU1
J 1
(-1075 1075);
DISPLAY 0.872340 (-1075 1075);
PAINT GREEN (-1075 1075);
DISPLAY INVISIBLE (-1075 1075);
FORCEADD INDUCTOR..1
(-2100 925);
FORCEPROP 1 LAST VALUE 0.12UH
J 2
(-2105 815);
DISPLAY 0.617021 (-2105 815);
PAINT SKYBLUE (-2105 815);
FORCEPROP 1 LASTPIN (-2000 925) $PN 2
J 2
(-1990 935);
DISPLAY 0.617021 (-1990 935);
PAINT WHITE (-1990 935);
FORCEPROP 1 LAST LOCATION L1D3
J 0
(-2100 975);
DISPLAY 0.617021 (-2100 975);
PAINT AQUA (-2100 975);
FORCEPROP 1 LAST PACK_TYPE SM
J 0
(-1935 815);
DISPLAY 0.617021 (-1935 815);
PAINT SKYBLUE (-1935 815);
FORCEPROP 1 LAST MATERIAL IND
J 0
(-2060 815);
DISPLAY 0.617021 (-2060 815);
PAINT SKYBLUE (-2060 815);
FORCEPROP 1 LASTPIN (-2200 925) $PN 1
J 0
(-2200 935);
DISPLAY 0.617021 (-2200 935);
PAINT WHITE (-2200 935);
FORCEPROP 1 LAST PART_NUMBER D92183-034
J 0
(-2225 875);
DISPLAY 0.617021 (-2225 875);
PAINT BLUE (-2225 875);
FORCEPROP 2 LAST CDS_LOCATION L1D3
J 0
(-2200 975);
DISPLAY 0.617021 (-2200 975);
PAINT AQUA (-2200 975);
DISPLAY INVISIBLE (-2200 975);
FORCEPROP 2 LAST CDS_LIB mstr_discrete
J 0
(-2100 925);
PAINT ORANGE (-2100 925);
DISPLAY INVISIBLE (-2100 925);
FORCEPROP 2 LAST ROOM PVCCIN_CPU1_PWR_VR
J 0
(-2200 1025);
DISPLAY 1.361702 (-2200 1025);
PAINT ORANGE (-2200 1025);
DISPLAY INVISIBLE (-2200 1025);
FORCEPROP 1 LAST PATH I16
J 0
(-2200 1075);
DISPLAY 0.978723 (-2200 1075);
PAINT ORANGE (-2200 1075);
DISPLAY INVISIBLE (-2200 1075);
FORCEPROP 2 LAST $SEC 1
J 0
(-2200 1125);
PAINT MONO (-2200 1125);
DISPLAY INVISIBLE (-2200 1125);
FORCEPROP 2 LAST CDS_SEC 1
J 0
(-2200 1125);
PAINT MONO (-2200 1125);
DISPLAY INVISIBLE (-2200 1125);
FORCEADD GND..1
(-1075 450);
FORCEPROP 3 LASTPIN (-1075 500) SIG_NAME GND\g
J 0
(-1065 510);
DISPLAY 0.659574 (-1065 510);
PAINT MONO (-1065 510);
DISPLAY INVISIBLE (-1065 510);
FORCEPROP 2 LAST ROOM PVCCIN_CPU1_PWR_VR
J 0
(-1625 525);
DISPLAY 1.936170 (-1625 525);
PAINT ORANGE (-1625 525);
DISPLAY INVISIBLE (-1625 525);
FORCEPROP 2 LAST BOM_COST PROC_VRD_VCCIN_CPU0
J 0
(-1450 525);
DISPLAY 1.446809 (-1450 525);
PAINT MONO (-1450 525);
DISPLAY INVISIBLE (-1450 525);
FORCEPROP 1 LAST PATH I17
J 0
(-1000 450);
DISPLAY 0.872340 (-1000 450);
PAINT AQUA (-1000 450);
DISPLAY INVISIBLE (-1000 450);
FORCEPROP 1 LAST SIZE 1B
J 0
(-1000 400);
DISPLAY 1.723404 (-1000 400);
PAINT GREEN (-1000 400);
DISPLAY INVISIBLE (-1000 400);
FORCEPROP 2 LAST CDS_LIB mstr_symbols
J 0
(-1075 450);
PAINT ORANGE (-1075 450);
DISPLAY INVISIBLE (-1075 450);
FORCEPROP 1 LAST VOLTAGE 0
J 0
(-1075 450);
PAINT SKYBLUE (-1075 450);
DISPLAY INVISIBLE (-1075 450);
FORCEPROP 1 LAST BODY_TYPE PLUMBING
J 0
(-1120 407);
DISPLAY 0.340426 (-1120 407);
PAINT GREEN (-1120 407);
DISPLAY INVISIBLE (-1120 407);
FORCEPROP 1 LAST HDL_POWER GND
J 0
(-1075 600);
DISPLAY 1.723404 (-1075 600);
PAINT GREEN (-1075 600);
DISPLAY INVISIBLE (-1075 600);
FORCEADD CAP_A..1
(-1525 775);
FORCEPROP 1 LAST VOLTAGE 4V
J 0
(-1475 775);
DISPLAY 0.617021 (-1475 775);
PAINT SKYBLUE (-1475 775);
FORCEPROP 1 LAST TOLERANCE 20%
J 0
(-1475 725);
DISPLAY 0.617021 (-1475 725);
PAINT SKYBLUE (-1475 725);
FORCEPROP 1 LASTPIN (-1525 675) $PN 2
J 0
(-1515 655);
DISPLAY 0.617021 (-1515 655);
PAINT ORANGE (-1515 655);
FORCEPROP 1 LAST MATERIAL X6S
J 0
(-1475 675);
DISPLAY 0.617021 (-1475 675);
PAINT SKYBLUE (-1475 675);
FORCEPROP 1 LAST PACK_TYPE 0603V
J 0
(-1475 575);
DISPLAY 0.617021 (-1475 575);
PAINT SKYBLUE (-1475 575);
FORCEPROP 1 LAST PART_NUMBER E15431-004
J 0
(-1475 625);
DISPLAY 0.617021 (-1475 625);
PAINT BLUE (-1475 625);
FORCEPROP 1 LAST VALUE 22.0UF
J 0
(-1475 825);
DISPLAY 0.617021 (-1475 825);
PAINT SKYBLUE (-1475 825);
FORCEPROP 1 LASTPIN (-1525 875) $PN 1
J 0
(-1515 855);
DISPLAY 0.617021 (-1515 855);
PAINT ORANGE (-1515 855);
FORCEPROP 1 LAST LOCATION C1E3
J 0
(-1475 875);
DISPLAY 0.617021 (-1475 875);
PAINT AQUA (-1475 875);
FORCEPROP 2 LAST CDS_LIB dev_discrete
J 0
(-1525 775);
PAINT ORANGE (-1525 775);
DISPLAY INVISIBLE (-1525 775);
FORCEPROP 2 LAST CDS_LOCATION C1E3
J 0
(-1475 875);
DISPLAY 0.617021 (-1475 875);
PAINT AQUA (-1475 875);
DISPLAY INVISIBLE (-1475 875);
FORCEPROP 2 LAST BOM_COST PROC_VRD_VCCIN_CPU0
J 0
(-1475 925);
DISPLAY 1.446809 (-1475 925);
PAINT MONO (-1475 925);
DISPLAY INVISIBLE (-1475 925);
FORCEPROP 2 LAST CDS_SEC 1
J 0
(-1475 925);
PAINT ORANGE (-1475 925);
DISPLAY INVISIBLE (-1475 925);
FORCEPROP 2 LAST SEC_TYPE 0603V
J 0
(-1470 975);
DISPLAY 1.021277 (-1470 975);
PAINT ORANGE (-1470 975);
DISPLAY INVISIBLE (-1470 975);
FORCEPROP 2 LAST SEC 1
J 0
(-1470 975);
DISPLAY 0.680851 (-1470 975);
PAINT MONO (-1470 975);
DISPLAY INVISIBLE (-1470 975);
FORCEPROP 1 LAST PATH I18
J 0
(-1475 925);
DISPLAY 0.978723 (-1475 925);
PAINT WHITE (-1475 925);
DISPLAY INVISIBLE (-1475 925);
FORCEPROP 2 LAST ROOM PVCCIN_CPU1_PWR_VR
J 0
(-1475 925);
DISPLAY 1.446809 (-1475 925);
PAINT MONO (-1475 925);
DISPLAY INVISIBLE (-1475 925);
FORCEADD GND..1
(-2725 3075);
FORCEPROP 3 LASTPIN (-2725 3125) SIG_NAME GND\g
J 0
(-2715 3135);
DISPLAY 0.659574 (-2715 3135);
PAINT MONO (-2715 3135);
DISPLAY INVISIBLE (-2715 3135);
FORCEPROP 2 LAST ROOM PVCCIN_CPU1_PWR_VR
J 0
(-3275 3150);
DISPLAY 1.936170 (-3275 3150);
PAINT ORANGE (-3275 3150);
DISPLAY INVISIBLE (-3275 3150);
FORCEPROP 2 LAST BOM_COST PROC_VRD_VCCIN_CPU0
J 0
(-3100 3150);
DISPLAY 1.446809 (-3100 3150);
PAINT MONO (-3100 3150);
DISPLAY INVISIBLE (-3100 3150);
FORCEPROP 1 LAST SIZE 1B
J 0
(-2650 3025);
DISPLAY 1.723404 (-2650 3025);
PAINT GREEN (-2650 3025);
DISPLAY INVISIBLE (-2650 3025);
FORCEPROP 1 LAST VOLTAGE 0
J 0
(-2725 3075);
PAINT SKYBLUE (-2725 3075);
DISPLAY INVISIBLE (-2725 3075);
FORCEPROP 2 LAST CDS_LIB mstr_symbols
J 0
(-2725 3075);
DISPLAY 1.936170 (-2725 3075);
PAINT ORANGE (-2725 3075);
DISPLAY INVISIBLE (-2725 3075);
FORCEPROP 1 LAST PATH I19
J 0
(-2650 3075);
DISPLAY 0.872340 (-2650 3075);
PAINT AQUA (-2650 3075);
DISPLAY INVISIBLE (-2650 3075);
FORCEPROP 1 LAST BODY_TYPE PLUMBING
J 0
(-2770 3032);
DISPLAY 0.340426 (-2770 3032);
PAINT GREEN (-2770 3032);
DISPLAY INVISIBLE (-2770 3032);
FORCEPROP 1 LAST HDL_POWER GND
J 0
(-2725 3225);
DISPLAY 1.723404 (-2725 3225);
PAINT GREEN (-2725 3225);
DISPLAY INVISIBLE (-2725 3225);
FORCEADD IR354XX..1
(-3450 3825);
FORCEPROP 2 LASTPIN (-3950 3625) $PN 39
J 2
(-3960 3635);
DISPLAY 0.617021 (-3960 3635);
PAINT ORANGE (-3960 3635);
FORCEPROP 2 LASTPIN (-3950 3475) $PN 32
J 2
(-3960 3485);
DISPLAY 0.617021 (-3960 3485);
PAINT ORANGE (-3960 3485);
FORCEPROP 2 LASTPIN (-3950 3525) $PN 33
J 2
(-3960 3535);
DISPLAY 0.617021 (-3960 3535);
PAINT ORANGE (-3960 3535);
FORCEPROP 2 LASTPIN (-3950 3725) $PN 34
J 2
(-3960 3735);
DISPLAY 0.617021 (-3960 3735);
PAINT ORANGE (-3960 3735);
FORCEPROP 2 LASTPIN (-3950 3825) $PN 6
J 2
(-3960 3835);
DISPLAY 0.617021 (-3960 3835);
PAINT ORANGE (-3960 3835);
FORCEPROP 2 LASTPIN (-3950 3975) $PN 1
J 2
(-3960 3985);
DISPLAY 0.617021 (-3960 3985);
PAINT ORANGE (-3960 3985);
FORCEPROP 2 LASTPIN (-3950 3875) $PN 41
J 2
(-3960 3885);
DISPLAY 0.617021 (-3960 3885);
PAINT ORANGE (-3960 3885);
FORCEPROP 2 LASTPIN (-2950 3875) $PN 36
J 0
(-2940 3885);
DISPLAY 0.617021 (-2940 3885);
PAINT ORANGE (-2940 3885);
FORCEPROP 2 LASTPIN (-3950 4075) $PN 35
J 2
(-3960 4085);
DISPLAY 0.617021 (-3960 4085);
PAINT ORANGE (-3960 4085);
FORCEPROP 2 LASTPIN (-3950 4275) $PN 25
J 2
(-3960 4285);
DISPLAY 0.617021 (-3960 4285);
PAINT ORANGE (-3960 4285);
FORCEPROP 2 LASTPIN (-3950 4175) $PN 4
J 2
(-3960 4185);
DISPLAY 0.617021 (-3960 4185);
PAINT ORANGE (-3960 4185);
FORCEPROP 2 LASTPIN (-3950 4325) $PN 30
J 2
(-3960 4335);
DISPLAY 0.617021 (-3960 4335);
PAINT ORANGE (-3960 4335);
FORCEPROP 1 LAST MATERIAL IC
J 0
(-3900 4550);
DISPLAY 0.617021 (-3900 4550);
PAINT SKYBLUE (-3900 4550);
FORCEPROP 2 LASTPIN (-2950 4375) $PN 38
J 0
(-2940 4385);
DISPLAY 0.617021 (-2940 4385);
PAINT ORANGE (-2940 4385);
FORCEPROP 2 LASTPIN (-2950 4125) $PN 31
J 0
(-2940 4135);
DISPLAY 0.617021 (-2940 4135);
PAINT ORANGE (-2940 4135);
FORCEPROP 2 LASTPIN (-3950 4375) $PN 3
J 2
(-3960 4385);
DISPLAY 0.617021 (-3960 4385);
PAINT ORANGE (-3960 4385);
FORCEPROP 1 LAST LOCATION EU1E2
J 0
(-3575 4550);
DISPLAY 0.617021 (-3575 4550);
PAINT AQUA (-3575 4550);
FORCEPROP 2 LASTPIN (-2950 3525) $PN 10
J 0
(-2940 3535);
DISPLAY 0.617021 (-2940 3535);
PAINT ORANGE (-2940 3535);
FORCEPROP 2 LASTPIN (-2950 3425) $PN 2
J 0
(-2940 3435);
DISPLAY 0.617021 (-2940 3435);
PAINT ORANGE (-2940 3435);
FORCEPROP 2 LASTPIN (-2950 3375) $PN 40
J 0
(-2940 3385);
DISPLAY 0.617021 (-2940 3385);
PAINT ORANGE (-2940 3385);
FORCEPROP 2 LASTPIN (-2950 3325) $PN 7
J 0
(-2940 3335);
DISPLAY 0.617021 (-2940 3335);
PAINT ORANGE (-2940 3335);
FORCEPROP 2 LASTPIN (-2950 3275) $PN 5
J 0
(-2940 3285);
DISPLAY 0.617021 (-2940 3285);
PAINT ORANGE (-2940 3285);
FORCEPROP 1 LAST VALUE IR35411
J 1
(-3450 4450);
DISPLAY 0.617021 (-3450 4450);
PAINT SKYBLUE (-3450 4450);
FORCEPROP 1 LAST PART_NUMBER H73688-001
J 0
(-3825 3125);
DISPLAY 0.617021 (-3825 3125);
PAINT BLUE (-3825 3125);
FORCEPROP 2 LASTPIN (-2950 4175) $PN 37
J 0
(-2940 4185);
DISPLAY 0.617021 (-2940 4185);
PAINT ORANGE (-2940 4185);
FORCEPROP 2 LAST ROOM PVCCIN_CPU1_PWR_VR
J 0
(-3700 2200);
DISPLAY 1.361702 (-3700 2200);
PAINT ORANGE (-3700 2200);
DISPLAY INVISIBLE (-3700 2200);
FORCEPROP 2 LAST CDS_LIB mstr_discrete
J 0
(-3450 3825);
PAINT ORANGE (-3450 3825);
DISPLAY INVISIBLE (-3450 3825);
FORCEPROP 1 LAST PACK_TYPE SM
J 0
(-3900 4675);
PAINT SKYBLUE (-3900 4675);
DISPLAY INVISIBLE (-3900 4675);
FORCEPROP 1 LAST PATH I20
J 0
(-3450 4575);
PAINT GREEN (-3450 4575);
DISPLAY INVISIBLE (-3450 4575);
FORCEPROP 2 LAST CDS_LOCATION EU1E2
J 0
(-3575 4550);
DISPLAY 0.765957 (-3575 4550);
PAINT AQUA (-3575 4550);
DISPLAY INVISIBLE (-3575 4550);
FORCEPROP 2 LAST SEC 1
J 0
(-3450 4625);
DISPLAY 0.680851 (-3450 4625);
PAINT MONO (-3450 4625);
DISPLAY INVISIBLE (-3450 4625);
FORCEPROP 2 LAST SEC_TYPE SM
J 0
(-3450 4625);
DISPLAY 1.021277 (-3450 4625);
PAINT ORANGE (-3450 4625);
DISPLAY INVISIBLE (-3450 4625);
FORCEADD GND..1
(-2775 550);
FORCEPROP 3 LASTPIN (-2775 600) SIG_NAME GND\g
J 0
(-2765 610);
DISPLAY 0.659574 (-2765 610);
PAINT MONO (-2765 610);
DISPLAY INVISIBLE (-2765 610);
FORCEPROP 2 LAST ROOM PVCCIN_CPU1_PWR_VR
J 0
(-3325 625);
DISPLAY 1.936170 (-3325 625);
PAINT ORANGE (-3325 625);
DISPLAY INVISIBLE (-3325 625);
FORCEPROP 2 LAST BOM_COST PROC_VRD_VCCIN_CPU0
J 0
(-3150 625);
DISPLAY 1.446809 (-3150 625);
PAINT MONO (-3150 625);
DISPLAY INVISIBLE (-3150 625);
FORCEPROP 1 LAST SIZE 1B
J 0
(-2700 500);
DISPLAY 1.723404 (-2700 500);
PAINT GREEN (-2700 500);
DISPLAY INVISIBLE (-2700 500);
FORCEPROP 1 LAST VOLTAGE 0
J 0
(-2775 550);
PAINT SKYBLUE (-2775 550);
DISPLAY INVISIBLE (-2775 550);
FORCEPROP 2 LAST CDS_LIB mstr_symbols
J 0
(-2775 550);
PAINT ORANGE (-2775 550);
DISPLAY INVISIBLE (-2775 550);
FORCEPROP 1 LAST PATH I23
J 0
(-2700 550);
DISPLAY 0.872340 (-2700 550);
PAINT AQUA (-2700 550);
DISPLAY INVISIBLE (-2700 550);
FORCEPROP 1 LAST BODY_TYPE PLUMBING
J 0
(-2820 507);
DISPLAY 0.340426 (-2820 507);
PAINT GREEN (-2820 507);
DISPLAY INVISIBLE (-2820 507);
FORCEPROP 1 LAST HDL_POWER GND
J 0
(-2775 700);
DISPLAY 1.723404 (-2775 700);
PAINT GREEN (-2775 700);
DISPLAY INVISIBLE (-2775 700);
FORCEADD IR354XX..1
(-3475 1225);
FORCEPROP 1 LAST PART_NUMBER H73688-001
J 0
(-3825 550);
DISPLAY 0.617021 (-3825 550);
PAINT BLUE (-3825 550);
FORCEPROP 2 LASTPIN (-2975 1575) $PN 37
J 0
(-2965 1585);
DISPLAY 0.617021 (-2965 1585);
PAINT ORANGE (-2965 1585);
FORCEPROP 2 LASTPIN (-3975 1025) $PN 39
J 2
(-3985 1035);
DISPLAY 0.617021 (-3985 1035);
PAINT ORANGE (-3985 1035);
FORCEPROP 2 LASTPIN (-3975 1125) $PN 34
J 2
(-3985 1135);
DISPLAY 0.617021 (-3985 1135);
PAINT ORANGE (-3985 1135);
FORCEPROP 2 LASTPIN (-3975 1225) $PN 6
J 2
(-3985 1235);
DISPLAY 0.617021 (-3985 1235);
PAINT ORANGE (-3985 1235);
FORCEPROP 2 LASTPIN (-3975 1275) $PN 41
J 2
(-3985 1285);
DISPLAY 0.617021 (-3985 1285);
PAINT ORANGE (-3985 1285);
FORCEPROP 2 LASTPIN (-3975 1375) $PN 1
J 2
(-3985 1385);
DISPLAY 0.617021 (-3985 1385);
PAINT ORANGE (-3985 1385);
FORCEPROP 2 LASTPIN (-3975 1475) $PN 35
J 2
(-3985 1485);
DISPLAY 0.617021 (-3985 1485);
PAINT ORANGE (-3985 1485);
FORCEPROP 2 LASTPIN (-3975 1575) $PN 4
J 2
(-3985 1585);
DISPLAY 0.617021 (-3985 1585);
PAINT ORANGE (-3985 1585);
FORCEPROP 2 LASTPIN (-3975 1675) $PN 25
J 2
(-3985 1685);
DISPLAY 0.617021 (-3985 1685);
PAINT ORANGE (-3985 1685);
FORCEPROP 2 LASTPIN (-3975 1725) $PN 30
J 2
(-3985 1735);
DISPLAY 0.617021 (-3985 1735);
PAINT ORANGE (-3985 1735);
FORCEPROP 2 LASTPIN (-3975 1775) $PN 3
J 2
(-3985 1785);
DISPLAY 0.617021 (-3985 1785);
PAINT ORANGE (-3985 1785);
FORCEPROP 1 LAST MATERIAL IC
J 0
(-3925 1950);
DISPLAY 0.617021 (-3925 1950);
PAINT SKYBLUE (-3925 1950);
FORCEPROP 2 LASTPIN (-2975 725) $PN 7
J 0
(-2965 735);
DISPLAY 0.617021 (-2965 735);
PAINT ORANGE (-2965 735);
FORCEPROP 2 LASTPIN (-2975 675) $PN 5
J 0
(-2965 685);
DISPLAY 0.617021 (-2965 685);
PAINT ORANGE (-2965 685);
FORCEPROP 2 LASTPIN (-2975 825) $PN 2
J 0
(-2965 835);
DISPLAY 0.617021 (-2965 835);
PAINT ORANGE (-2965 835);
FORCEPROP 2 LASTPIN (-2975 1525) $PN 31
J 0
(-2965 1535);
DISPLAY 0.617021 (-2965 1535);
PAINT ORANGE (-2965 1535);
FORCEPROP 2 LASTPIN (-2975 1775) $PN 38
J 0
(-2965 1785);
DISPLAY 0.617021 (-2965 1785);
PAINT ORANGE (-2965 1785);
FORCEPROP 2 LASTPIN (-2975 1275) $PN 36
J 0
(-2965 1285);
DISPLAY 0.617021 (-2965 1285);
PAINT ORANGE (-2965 1285);
FORCEPROP 2 LASTPIN (-2975 925) $PN 10
J 0
(-2965 935);
DISPLAY 0.617021 (-2965 935);
PAINT ORANGE (-2965 935);
FORCEPROP 1 LAST LOCATION EU1D4
J 0
(-3575 1950);
DISPLAY 0.617021 (-3575 1950);
PAINT AQUA (-3575 1950);
FORCEPROP 2 LASTPIN (-3975 875) $PN 32
J 2
(-3985 885);
DISPLAY 0.617021 (-3985 885);
PAINT ORANGE (-3985 885);
FORCEPROP 2 LASTPIN (-3975 925) $PN 33
J 2
(-3985 935);
DISPLAY 0.617021 (-3985 935);
PAINT ORANGE (-3985 935);
FORCEPROP 1 LAST VALUE IR35411
J 1
(-3475 1850);
DISPLAY 0.617021 (-3475 1850);
PAINT SKYBLUE (-3475 1850);
FORCEPROP 2 LASTPIN (-2975 775) $PN 40
J 0
(-2965 785);
DISPLAY 0.617021 (-2965 785);
PAINT ORANGE (-2965 785);
FORCEPROP 2 LAST ROOM PVCCIN_CPU1_PWR_VR
J 0
(-9275 2000);
DISPLAY 1.361702 (-9275 2000);
PAINT ORANGE (-9275 2000);
DISPLAY INVISIBLE (-9275 2000);
FORCEPROP 1 LAST PATH I24
J 0
(-3475 1975);
PAINT GREEN (-3475 1975);
DISPLAY INVISIBLE (-3475 1975);
FORCEPROP 2 LAST CDS_LOCATION EU1D4
J 0
(-3575 1950);
DISPLAY 0.765957 (-3575 1950);
PAINT AQUA (-3575 1950);
DISPLAY INVISIBLE (-3575 1950);
FORCEPROP 2 LAST CDS_LIB mstr_discrete
J 0
(-3475 1225);
PAINT ORANGE (-3475 1225);
DISPLAY INVISIBLE (-3475 1225);
FORCEPROP 2 LAST SEC 1
J 0
(-3475 2025);
DISPLAY 0.680851 (-3475 2025);
PAINT MONO (-3475 2025);
DISPLAY INVISIBLE (-3475 2025);
FORCEPROP 2 LAST SEC_TYPE SM
J 0
(-3475 2025);
DISPLAY 1.021277 (-3475 2025);
PAINT ORANGE (-3475 2025);
DISPLAY INVISIBLE (-3475 2025);
FORCEPROP 1 LAST PACK_TYPE SM
J 0
(-3925 2075);
PAINT SKYBLUE (-3925 2075);
DISPLAY INVISIBLE (-3925 2075);
FORCEADD RES..1
(-5700 4625);
FORCEPROP 1 LAST VALUE 1.0
J 2
(-5800 4500);
DISPLAY 0.617021 (-5800 4500);
PAINT SKYBLUE (-5800 4500);
FORCEPROP 1 LAST TOLERANCE 1%
J 0
(-5750 4500);
DISPLAY 0.617021 (-5750 4500);
PAINT SKYBLUE (-5750 4500);
FORCEPROP 1 LAST WATTAGE 1/16W
J 2
(-5675 4450);
DISPLAY 0.617021 (-5675 4450);
PAINT SKYBLUE (-5675 4450);
FORCEPROP 1 LASTPIN (-5800 4625) $PN 1
J 0
(-5788 4637);
DISPLAY 0.617021 (-5788 4637);
PAINT ORANGE (-5788 4637);
FORCEPROP 1 LAST LOCATION R9R2
J 0
(-5750 4675);
DISPLAY 0.617021 (-5750 4675);
PAINT AQUA (-5750 4675);
FORCEPROP 1 LASTPIN (-5600 4625) $PN 2
J 0
(-5638 4637);
DISPLAY 0.617021 (-5638 4637);
PAINT ORANGE (-5638 4637);
FORCEPROP 1 LAST PACK_TYPE 0402
J 0
(-5650 4500);
DISPLAY 0.617021 (-5650 4500);
PAINT SKYBLUE (-5650 4500);
FORCEPROP 1 LAST PART_NUMBER G21796-090
J 0
(-5825 4550);
DISPLAY 0.617021 (-5825 4550);
PAINT BLUE (-5825 4550);
FORCEPROP 1 LAST MATERIAL CHIP
J 0
(-5625 4450);
DISPLAY 0.617021 (-5625 4450);
PAINT SKYBLUE (-5625 4450);
FORCEPROP 2 LAST CDS_LIB mstr_discrete
J 0
(-5700 4625);
PAINT ORANGE (-5700 4625);
DISPLAY INVISIBLE (-5700 4625);
FORCEPROP 2 LAST SEC 1
J 0
(-5750 4825);
DISPLAY 0.680851 (-5750 4825);
PAINT MONO (-5750 4825);
DISPLAY INVISIBLE (-5750 4825);
FORCEPROP 2 LAST CDS_LOCATION R9R2
J 0
(-5750 4675);
DISPLAY 0.617021 (-5750 4675);
PAINT AQUA (-5750 4675);
DISPLAY INVISIBLE (-5750 4675);
FORCEPROP 2 LAST ROOM PVCCIN_CPU1_PWR_VR
J 0
(-5750 4725);
DISPLAY 1.361702 (-5750 4725);
PAINT ORANGE (-5750 4725);
DISPLAY INVISIBLE (-5750 4725);
FORCEPROP 1 LAST PATH I26
J 0
(-5750 4775);
DISPLAY 0.978723 (-5750 4775);
PAINT WHITE (-5750 4775);
DISPLAY INVISIBLE (-5750 4775);
FORCEPROP 2 LAST SEC_TYPE 0402
J 0
(-5750 4825);
DISPLAY 1.021277 (-5750 4825);
PAINT ORANGE (-5750 4825);
DISPLAY INVISIBLE (-5750 4825);
FORCEADD VCC_CORE..1
(-7525 4475);
FORCEPROP 3 LASTPIN (-7525 4425) SIG_NAME VR_FET_SW_P12V_STBY_PVCCIN_CPU1\g
J 0
(-7515 4435);
DISPLAY 0.659574 (-7515 4435);
PAINT MONO (-7515 4435);
DISPLAY INVISIBLE (-7515 4435);
FORCEPROP 1 LAST HDL_POWER VR_FET_SW_P12V_STBY_PVCCIN_CPU1
J 1
(-7450 4525);
DISPLAY 0.617021 (-7450 4525);
PAINT GREEN (-7450 4525);
FORCEPROP 2 LAST CDS_LIB mstr_symbols
J 0
(-7525 4475);
DISPLAY 1.936170 (-7525 4475);
PAINT ORANGE (-7525 4475);
DISPLAY INVISIBLE (-7525 4475);
FORCEPROP 1 LAST PATH I27
J 0
(-7475 4500);
DISPLAY 0.872340 (-7475 4500);
PAINT AQUA (-7475 4500);
DISPLAY INVISIBLE (-7475 4500);
FORCEADD CAP..1
(-5250 4100);
FORCEPROP 1 LASTPIN (-5250 4000) $PN 2
J 0
(-5240 3980);
DISPLAY 0.617021 (-5240 3980);
PAINT ORANGE (-5240 3980);
FORCEPROP 1 LAST MATERIAL X7R
J 0
(-5200 4000);
DISPLAY 0.617021 (-5200 4000);
PAINT SKYBLUE (-5200 4000);
FORCEPROP 1 LAST PACK_TYPE 0402
J 0
(-5200 3900);
DISPLAY 0.617021 (-5200 3900);
PAINT SKYBLUE (-5200 3900);
FORCEPROP 1 LAST TOLERANCE 10%
J 0
(-5200 4050);
DISPLAY 0.617021 (-5200 4050);
PAINT SKYBLUE (-5200 4050);
FORCEPROP 1 LAST PART_NUMBER A36096-155
J 0
(-5200 3950);
DISPLAY 0.617021 (-5200 3950);
PAINT BLUE (-5200 3950);
FORCEPROP 1 LASTPIN (-5250 4200) $PN 1
J 0
(-5240 4180);
DISPLAY 0.617021 (-5240 4180);
PAINT ORANGE (-5240 4180);
FORCEPROP 1 LAST VOLTAGE 16V
J 0
(-5200 4100);
DISPLAY 0.617021 (-5200 4100);
PAINT SKYBLUE (-5200 4100);
FORCEPROP 1 LAST VALUE 0.22UF
J 0
(-5200 4150);
DISPLAY 0.617021 (-5200 4150);
PAINT SKYBLUE (-5200 4150);
FORCEPROP 1 LAST LOCATION C1E7
J 0
(-5200 4200);
DISPLAY 0.617021 (-5200 4200);
PAINT AQUA (-5200 4200);
FORCEPROP 2 LAST CDS_LIB mstr_discrete
J 0
(-5250 4100);
PAINT ORANGE (-5250 4100);
DISPLAY INVISIBLE (-5250 4100);
FORCEPROP 2 LAST ROOM PVCCIN_CPU1_PWR_VR
J 0
(-5200 4250);
DISPLAY 1.361702 (-5200 4250);
PAINT ORANGE (-5200 4250);
DISPLAY INVISIBLE (-5200 4250);
FORCEPROP 1 LAST PATH I28
J 0
(-5200 4250);
DISPLAY 0.978723 (-5200 4250);
PAINT WHITE (-5200 4250);
DISPLAY INVISIBLE (-5200 4250);
FORCEPROP 2 LAST CDS_LOCATION C1E7
J 0
(-5200 4200);
DISPLAY 0.617021 (-5200 4200);
PAINT AQUA (-5200 4200);
DISPLAY INVISIBLE (-5200 4200);
FORCEPROP 2 LAST SEC 1
J 0
(-5200 4300);
DISPLAY 0.680851 (-5200 4300);
PAINT MONO (-5200 4300);
DISPLAY INVISIBLE (-5200 4300);
FORCEPROP 2 LAST SEC_TYPE 0402
J 0
(-5200 4300);
DISPLAY 1.021277 (-5200 4300);
PAINT ORANGE (-5200 4300);
DISPLAY INVISIBLE (-5200 4300);
FORCEADD CAP_A..1
R 2
(-5375 4100);
FORCEPROP 1 LASTPIN (-5375 4000) $PN 2
J 2
(-5385 3980);
DISPLAY 0.617021 (-5385 3980);
PAINT ORANGE (-5385 3980);
FORCEPROP 1 LAST MATERIAL X6S
J 2
(-5425 4000);
DISPLAY 0.617021 (-5425 4000);
PAINT SKYBLUE (-5425 4000);
FORCEPROP 1 LAST TOLERANCE 10%
J 2
(-5425 4050);
DISPLAY 0.617021 (-5425 4050);
PAINT SKYBLUE (-5425 4050);
FORCEPROP 1 LASTPIN (-5375 4200) $PN 1
J 2
(-5385 4180);
DISPLAY 0.617021 (-5385 4180);
PAINT ORANGE (-5385 4180);
FORCEPROP 1 LAST VOLTAGE 6.3V
J 2
(-5425 4100);
DISPLAY 0.617021 (-5425 4100);
PAINT SKYBLUE (-5425 4100);
FORCEPROP 1 LAST VALUE 1.0UF
J 2
(-5425 4150);
DISPLAY 0.617021 (-5425 4150);
PAINT SKYBLUE (-5425 4150);
FORCEPROP 1 LAST LOCATION C1E6
J 2
(-5425 4200);
DISPLAY 0.617021 (-5425 4200);
PAINT AQUA (-5425 4200);
FORCEPROP 1 LAST PACK_TYPE 0402V
J 2
(-5425 3900);
DISPLAY 0.617021 (-5425 3900);
PAINT SKYBLUE (-5425 3900);
FORCEPROP 1 LAST PART_NUMBER D97712-004
J 2
(-5425 3950);
DISPLAY 0.617021 (-5425 3950);
PAINT BLUE (-5425 3950);
FORCEPROP 2 LAST SEC 1
J 0
(-5425 4300);
DISPLAY 0.680851 (-5425 4300);
PAINT MONO (-5425 4300);
DISPLAY INVISIBLE (-5425 4300);
FORCEPROP 2 LAST CDS_LOCATION C1E6
J 2
(-5425 4200);
DISPLAY 0.617021 (-5425 4200);
PAINT AQUA (-5425 4200);
DISPLAY INVISIBLE (-5425 4200);
FORCEPROP 2 LAST CDS_SEC 1
J 0
(-5425 4250);
PAINT ORANGE (-5425 4250);
DISPLAY INVISIBLE (-5425 4250);
FORCEPROP 2 LAST SEC_TYPE 0402V
J 0
(-5425 4300);
DISPLAY 1.021277 (-5425 4300);
PAINT ORANGE (-5425 4300);
DISPLAY INVISIBLE (-5425 4300);
FORCEPROP 2 LAST ROOM PVCCIN_CPU1_PWR_VR
J 0
(-5425 4250);
DISPLAY 1.361702 (-5425 4250);
PAINT ORANGE (-5425 4250);
DISPLAY INVISIBLE (-5425 4250);
FORCEPROP 1 LAST PATH I29
J 2
(-5425 4250);
DISPLAY 0.978723 (-5425 4250);
PAINT WHITE (-5425 4250);
DISPLAY INVISIBLE (-5425 4250);
FORCEPROP 2 LAST CDS_LIB dev_discrete
J 0
(-5375 4100);
PAINT ORANGE (-5375 4100);
DISPLAY INVISIBLE (-5375 4100);
FORCEADD OFFPAGE..2
(-1875 4075);
FORCEPROP 2 LAST $XR0 207 
J 0
(-1686 4075);
DISPLAY 0.638298 (-1686 4075);
PAINT MONO (-1686 4075);
FORCEPROP 2 LAST $XR1 208 
J 0
(-1566 4075);
DISPLAY 0.638298 (-1566 4075);
PAINT MONO (-1566 4075);
FORCEPROP 2 LAST $XR2 209 
J 0
(-1446 4075);
DISPLAY 0.638298 (-1446 4075);
PAINT MONO (-1446 4075);
FORCEPROP 2 LAST $XR3 206 
J 0
(-1326 4075);
DISPLAY 0.638298 (-1326 4075);
PAINT MONO (-1326 4075);
FORCEPROP 2 LAST PATH I3
J 0
(-1445 4125);
DISPLAY 1.021277 (-1445 4125);
PAINT ORANGE (-1445 4125);
DISPLAY INVISIBLE (-1445 4125);
FORCEPROP 2 LAST BOM_COST PROC_VRD_VCCIN_CPU0
J 0
(-1675 4125);
DISPLAY 1.446809 (-1675 4125);
PAINT MONO (-1675 4125);
DISPLAY INVISIBLE (-1675 4125);
FORCEPROP 2 LAST CDS_LIB mstr_standard
J 0
(-1875 4075);
PAINT ORANGE (-1875 4075);
DISPLAY INVISIBLE (-1875 4075);
FORCEPROP 2 LAST ROOM PVCCIN_CPU1_PWR_VR
J 0
(-2275 4150);
DISPLAY 1.936170 (-2275 4150);
PAINT ORANGE (-2275 4150);
DISPLAY INVISIBLE (-2275 4150);
FORCEPROP 1 LAST OFFPAGE TRUE
J 0
(-1550 3950);
DISPLAY 1.723404 (-1550 3950);
PAINT GREEN (-1550 3950);
DISPLAY INVISIBLE (-1550 3950);
FORCEPROP 1 LAST COMMENT_BODY TRUE
J 0
(-1920 3980);
DISPLAY 1.723404 (-1920 3980);
PAINT GREEN (-1920 3980);
DISPLAY INVISIBLE (-1920 3980);
FORCEADD CAP..1
R 2
(-6000 3475);
FORCEPROP 1 LAST VALUE 0.220UF
J 2
(-6050 3525);
DISPLAY 0.617021 (-6050 3525);
PAINT SKYBLUE (-6050 3525);
FORCEPROP 1 LAST LOCATION C1E11
J 2
(-6050 3575);
DISPLAY 0.617021 (-6050 3575);
PAINT AQUA (-6050 3575);
FORCEPROP 1 LAST VOLTAGE 16V
J 2
(-6050 3475);
DISPLAY 0.617021 (-6050 3475);
PAINT SKYBLUE (-6050 3475);
FORCEPROP 1 LAST MATERIAL X7R
J 2
(-6050 3375);
DISPLAY 0.617021 (-6050 3375);
PAINT SKYBLUE (-6050 3375);
FORCEPROP 1 LAST PACK_TYPE 0402
J 2
(-6050 3275);
DISPLAY 0.617021 (-6050 3275);
PAINT SKYBLUE (-6050 3275);
FORCEPROP 1 LAST PART_NUMBER A36096-104
J 2
(-6050 3325);
DISPLAY 0.617021 (-6050 3325);
PAINT BLUE (-6050 3325);
FORCEPROP 1 LASTPIN (-6000 3375) $PN 2
J 2
(-6010 3355);
DISPLAY 0.617021 (-6010 3355);
PAINT ORANGE (-6010 3355);
FORCEPROP 1 LASTPIN (-6000 3575) $PN 1
J 2
(-6010 3555);
DISPLAY 0.617021 (-6010 3555);
PAINT ORANGE (-6010 3555);
FORCEPROP 1 LAST TOLERANCE 10%
J 2
(-6050 3425);
DISPLAY 0.617021 (-6050 3425);
PAINT SKYBLUE (-6050 3425);
FORCEPROP 2 LAST CDS_LIB mstr_discrete
J 0
(-6000 3475);
PAINT ORANGE (-6000 3475);
DISPLAY INVISIBLE (-6000 3475);
FORCEPROP 2 LAST CDS_LOCATION C1E11
J 2
(-6050 3575);
DISPLAY 0.617021 (-6050 3575);
PAINT AQUA (-6050 3575);
DISPLAY INVISIBLE (-6050 3575);
FORCEPROP 2 LAST NO_XNET_CONNECTION 1
J 0
(-6050 3675);
PAINT MONO (-6050 3675);
DISPLAY INVISIBLE (-6050 3675);
FORCEPROP 1 LAST PATH I30
J 2
(-6050 3625);
DISPLAY 0.978723 (-6050 3625);
PAINT WHITE (-6050 3625);
DISPLAY INVISIBLE (-6050 3625);
FORCEPROP 2 LAST ROOM PVCCIN_CPU1_PWR_VR
J 0
(-6075 3625);
DISPLAY 1.361702 (-6075 3625);
PAINT ORANGE (-6075 3625);
DISPLAY INVISIBLE (-6075 3625);
FORCEPROP 2 LAST SEC_TYPE 0402
J 0
(-6050 3675);
DISPLAY 1.021277 (-6050 3675);
PAINT ORANGE (-6050 3675);
DISPLAY INVISIBLE (-6050 3675);
FORCEPROP 0 LAST SPOF TRUE
J 0
(-6050 3675);
DISPLAY 1.021277 (-6050 3675);
PAINT ORANGE (-6050 3675);
DISPLAY INVISIBLE (-6050 3675);
FORCEPROP 2 LAST SEC 1
J 0
(-6050 3675);
PAINT MONO (-6050 3675);
DISPLAY INVISIBLE (-6050 3675);
FORCEADD CAP..1
(-5950 4075);
FORCEPROP 1 LASTPIN (-5950 3975) $PN 2
J 0
(-5940 3955);
DISPLAY 0.617021 (-5940 3955);
PAINT ORANGE (-5940 3955);
FORCEPROP 1 LAST MATERIAL X6S
J 0
(-5900 3975);
DISPLAY 0.617021 (-5900 3975);
PAINT SKYBLUE (-5900 3975);
FORCEPROP 1 LAST PACK_TYPE 0402
J 0
(-5900 3875);
DISPLAY 0.617021 (-5900 3875);
PAINT SKYBLUE (-5900 3875);
FORCEPROP 1 LAST PART_NUMBER D97712-011
J 0
(-5900 3925);
DISPLAY 0.617021 (-5900 3925);
PAINT BLUE (-5900 3925);
FORCEPROP 1 LAST VOLTAGE 16V
J 0
(-5900 4075);
DISPLAY 0.617021 (-5900 4075);
PAINT SKYBLUE (-5900 4075);
FORCEPROP 1 LASTPIN (-5950 4175) $PN 1
J 0
(-5940 4155);
DISPLAY 0.617021 (-5940 4155);
PAINT ORANGE (-5940 4155);
FORCEPROP 1 LAST VALUE 1.0UF
J 0
(-5900 4125);
DISPLAY 0.617021 (-5900 4125);
PAINT SKYBLUE (-5900 4125);
FORCEPROP 1 LAST LOCATION C1E8
J 0
(-5900 4175);
DISPLAY 0.617021 (-5900 4175);
PAINT AQUA (-5900 4175);
FORCEPROP 1 LAST TOLERANCE 10%
J 0
(-5900 4025);
DISPLAY 0.617021 (-5900 4025);
PAINT SKYBLUE (-5900 4025);
FORCEPROP 2 LAST CDS_LIB mstr_discrete
J 0
(-5950 4075);
PAINT ORANGE (-5950 4075);
DISPLAY INVISIBLE (-5950 4075);
FORCEPROP 2 LAST ROOM PVCCIN_CPU1_PWR_VR
J 0
(-5900 4225);
DISPLAY 1.361702 (-5900 4225);
PAINT ORANGE (-5900 4225);
DISPLAY INVISIBLE (-5900 4225);
FORCEPROP 1 LAST PATH I32
J 0
(-5900 4225);
DISPLAY 0.978723 (-5900 4225);
PAINT WHITE (-5900 4225);
DISPLAY INVISIBLE (-5900 4225);
FORCEPROP 2 LAST CDS_LOCATION C1E8
J 0
(-5900 4175);
DISPLAY 0.617021 (-5900 4175);
PAINT AQUA (-5900 4175);
DISPLAY INVISIBLE (-5900 4175);
FORCEPROP 2 LAST SEC_TYPE 0402
J 0
(-5900 4275);
DISPLAY 1.021277 (-5900 4275);
PAINT ORANGE (-5900 4275);
DISPLAY INVISIBLE (-5900 4275);
FORCEPROP 2 LAST SEC 1
J 0
(-5900 4275);
DISPLAY 0.680851 (-5900 4275);
PAINT MONO (-5900 4275);
DISPLAY INVISIBLE (-5900 4275);
FORCEADD CAP_A..1
(-6250 4100);
FORCEPROP 1 LASTPIN (-6250 4000) $PN 2
J 0
(-6240 3980);
DISPLAY 0.617021 (-6240 3980);
PAINT ORANGE (-6240 3980);
FORCEPROP 1 LAST MATERIAL X7R
J 0
(-6200 4000);
DISPLAY 0.617021 (-6200 4000);
PAINT SKYBLUE (-6200 4000);
FORCEPROP 1 LAST TOLERANCE 10%
J 0
(-6200 4050);
DISPLAY 0.617021 (-6200 4050);
PAINT SKYBLUE (-6200 4050);
FORCEPROP 1 LAST PART_NUMBER A36096-030
J 0
(-6200 3950);
DISPLAY 0.617021 (-6200 3950);
PAINT BLUE (-6200 3950);
FORCEPROP 1 LASTPIN (-6250 4200) $PN 1
J 0
(-6240 4180);
DISPLAY 0.617021 (-6240 4180);
PAINT ORANGE (-6240 4180);
FORCEPROP 1 LAST VALUE 0.1UF
J 0
(-6200 4150);
DISPLAY 0.617021 (-6200 4150);
PAINT SKYBLUE (-6200 4150);
FORCEPROP 1 LAST LOCATION C1E14
J 0
(-6200 4200);
DISPLAY 0.617021 (-6200 4200);
PAINT AQUA (-6200 4200);
FORCEPROP 1 LAST VOLTAGE 16V
J 0
(-6200 4100);
DISPLAY 0.617021 (-6200 4100);
PAINT SKYBLUE (-6200 4100);
FORCEPROP 1 LAST PACK_TYPE 0402V
J 0
(-6200 3900);
DISPLAY 0.617021 (-6200 3900);
PAINT SKYBLUE (-6200 3900);
FORCEPROP 2 LAST CDS_LIB dev_discrete
J 0
(-6250 4100);
PAINT ORANGE (-6250 4100);
DISPLAY INVISIBLE (-6250 4100);
FORCEPROP 2 LAST CDS_LOCATION C1E14
J 0
(-6200 4200);
DISPLAY 0.617021 (-6200 4200);
PAINT AQUA (-6200 4200);
DISPLAY INVISIBLE (-6200 4200);
FORCEPROP 1 LAST PATH I33
J 0
(-6200 4250);
DISPLAY 0.978723 (-6200 4250);
PAINT WHITE (-6200 4250);
DISPLAY INVISIBLE (-6200 4250);
FORCEPROP 2 LAST ROOM PVCCIN_CPU1_PWR_VR
J 0
(-6200 4250);
DISPLAY 1.361702 (-6200 4250);
PAINT ORANGE (-6200 4250);
DISPLAY INVISIBLE (-6200 4250);
FORCEPROP 2 LAST CDS_SEC 1
J 0
(-6200 4250);
PAINT ORANGE (-6200 4250);
DISPLAY INVISIBLE (-6200 4250);
FORCEPROP 2 LAST SEC_TYPE 0402V
J 0
(-6200 4300);
DISPLAY 1.021277 (-6200 4300);
PAINT ORANGE (-6200 4300);
DISPLAY INVISIBLE (-6200 4300);
FORCEPROP 2 LAST SEC 1
J 0
(-6200 4300);
DISPLAY 0.680851 (-6200 4300);
PAINT MONO (-6200 4300);
DISPLAY INVISIBLE (-6200 4300);
FORCEADD CAP..1
(-6575 4100);
FORCEPROP 1 LAST MATERIAL X6S
J 0
(-6525 4000);
DISPLAY 0.617021 (-6525 4000);
PAINT SKYBLUE (-6525 4000);
FORCEPROP 1 LASTPIN (-6575 4000) $PN 2
J 0
(-6565 3980);
DISPLAY 0.617021 (-6565 3980);
PAINT ORANGE (-6565 3980);
FORCEPROP 1 LASTPIN (-6575 4200) $PN 1
J 0
(-6565 4180);
DISPLAY 0.617021 (-6565 4180);
PAINT ORANGE (-6565 4180);
FORCEPROP 1 LAST VALUE 1.0UF
J 0
(-6525 4150);
DISPLAY 0.617021 (-6525 4150);
PAINT SKYBLUE (-6525 4150);
FORCEPROP 1 LAST LOCATION C1E13
J 0
(-6525 4200);
DISPLAY 0.617021 (-6525 4200);
PAINT AQUA (-6525 4200);
FORCEPROP 1 LAST VOLTAGE 16V
J 0
(-6525 4100);
DISPLAY 0.617021 (-6525 4100);
PAINT SKYBLUE (-6525 4100);
FORCEPROP 1 LAST TOLERANCE 10%
J 0
(-6525 4050);
DISPLAY 0.617021 (-6525 4050);
PAINT SKYBLUE (-6525 4050);
FORCEPROP 1 LAST PART_NUMBER D97712-011
J 0
(-6525 3950);
DISPLAY 0.617021 (-6525 3950);
PAINT BLUE (-6525 3950);
FORCEPROP 1 LAST PACK_TYPE 0402
J 0
(-6525 3900);
DISPLAY 0.617021 (-6525 3900);
PAINT SKYBLUE (-6525 3900);
FORCEPROP 2 LAST CDS_LIB mstr_discrete
J 0
(-6575 4100);
PAINT ORANGE (-6575 4100);
DISPLAY INVISIBLE (-6575 4100);
FORCEPROP 2 LAST ROOM PVCCIN_CPU1_PWR_VR
J 0
(-6525 4250);
DISPLAY 1.361702 (-6525 4250);
PAINT ORANGE (-6525 4250);
DISPLAY INVISIBLE (-6525 4250);
FORCEPROP 1 LAST PATH I34
J 0
(-6525 4250);
DISPLAY 0.978723 (-6525 4250);
PAINT WHITE (-6525 4250);
DISPLAY INVISIBLE (-6525 4250);
FORCEPROP 2 LAST CDS_LOCATION C1E13
J 0
(-6525 4200);
DISPLAY 0.617021 (-6525 4200);
PAINT AQUA (-6525 4200);
DISPLAY INVISIBLE (-6525 4200);
FORCEPROP 2 LAST SEC 1
J 0
(-6525 4300);
DISPLAY 0.680851 (-6525 4300);
PAINT MONO (-6525 4300);
DISPLAY INVISIBLE (-6525 4300);
FORCEPROP 2 LAST SEC_TYPE 0402
J 0
(-6525 4300);
DISPLAY 1.021277 (-6525 4300);
PAINT ORANGE (-6525 4300);
DISPLAY INVISIBLE (-6525 4300);
FORCEADD CAP..1
(-5075 1550);
FORCEPROP 1 LAST PART_NUMBER A36096-155
J 0
(-5025 1400);
DISPLAY 0.617021 (-5025 1400);
PAINT BLUE (-5025 1400);
FORCEPROP 1 LASTPIN (-5075 1450) $PN 2
J 0
(-5065 1430);
DISPLAY 0.617021 (-5065 1430);
PAINT ORANGE (-5065 1430);
FORCEPROP 1 LAST MATERIAL X7R
J 0
(-5025 1450);
DISPLAY 0.617021 (-5025 1450);
PAINT SKYBLUE (-5025 1450);
FORCEPROP 1 LAST PACK_TYPE 0402
J 0
(-5025 1350);
DISPLAY 0.617021 (-5025 1350);
PAINT SKYBLUE (-5025 1350);
FORCEPROP 1 LAST TOLERANCE 10%
J 0
(-5025 1500);
DISPLAY 0.617021 (-5025 1500);
PAINT SKYBLUE (-5025 1500);
FORCEPROP 1 LASTPIN (-5075 1650) $PN 1
J 0
(-5065 1630);
DISPLAY 0.617021 (-5065 1630);
PAINT ORANGE (-5065 1630);
FORCEPROP 1 LAST LOCATION C1E25
J 0
(-5025 1650);
DISPLAY 0.617021 (-5025 1650);
PAINT AQUA (-5025 1650);
FORCEPROP 1 LAST VALUE 0.22UF
J 0
(-5025 1600);
DISPLAY 0.617021 (-5025 1600);
PAINT SKYBLUE (-5025 1600);
FORCEPROP 1 LAST VOLTAGE 16V
J 0
(-5025 1550);
DISPLAY 0.617021 (-5025 1550);
PAINT SKYBLUE (-5025 1550);
FORCEPROP 2 LAST ROOM PVCCIN_CPU1_PWR_VR
J 0
(-5025 1700);
DISPLAY 1.361702 (-5025 1700);
PAINT ORANGE (-5025 1700);
DISPLAY INVISIBLE (-5025 1700);
FORCEPROP 2 LAST CDS_LIB mstr_discrete
J 0
(-5075 1550);
PAINT ORANGE (-5075 1550);
DISPLAY INVISIBLE (-5075 1550);
FORCEPROP 2 LAST SEC 1
J 0
(-5025 1750);
DISPLAY 0.680851 (-5025 1750);
PAINT MONO (-5025 1750);
DISPLAY INVISIBLE (-5025 1750);
FORCEPROP 1 LAST PATH I36
J 0
(-5025 1700);
DISPLAY 0.978723 (-5025 1700);
PAINT WHITE (-5025 1700);
DISPLAY INVISIBLE (-5025 1700);
FORCEPROP 2 LAST SEC_TYPE 0402
J 0
(-5025 1750);
DISPLAY 1.021277 (-5025 1750);
PAINT ORANGE (-5025 1750);
DISPLAY INVISIBLE (-5025 1750);
FORCEADD CAP_A..1
R 2
(-5250 1550);
FORCEPROP 1 LAST PACK_TYPE 0402V
J 2
(-5300 1350);
DISPLAY 0.617021 (-5300 1350);
PAINT SKYBLUE (-5300 1350);
FORCEPROP 1 LASTPIN (-5250 1450) $PN 2
J 2
(-5260 1430);
DISPLAY 0.617021 (-5260 1430);
PAINT ORANGE (-5260 1430);
FORCEPROP 1 LAST VOLTAGE 6.3V
J 2
(-5300 1550);
DISPLAY 0.617021 (-5300 1550);
PAINT SKYBLUE (-5300 1550);
FORCEPROP 1 LAST VALUE 1.0UF
J 2
(-5300 1600);
DISPLAY 0.617021 (-5300 1600);
PAINT SKYBLUE (-5300 1600);
FORCEPROP 1 LAST LOCATION C1E23
J 2
(-5300 1650);
DISPLAY 0.617021 (-5300 1650);
PAINT AQUA (-5300 1650);
FORCEPROP 1 LASTPIN (-5250 1650) $PN 1
J 2
(-5260 1630);
DISPLAY 0.617021 (-5260 1630);
PAINT ORANGE (-5260 1630);
FORCEPROP 1 LAST PART_NUMBER D97712-004
J 2
(-5300 1400);
DISPLAY 0.617021 (-5300 1400);
PAINT BLUE (-5300 1400);
FORCEPROP 1 LAST MATERIAL X6S
J 2
(-5300 1450);
DISPLAY 0.617021 (-5300 1450);
PAINT SKYBLUE (-5300 1450);
FORCEPROP 1 LAST TOLERANCE 10%
J 2
(-5300 1500);
DISPLAY 0.617021 (-5300 1500);
PAINT SKYBLUE (-5300 1500);
FORCEPROP 2 LAST CDS_LIB dev_discrete
J 0
(-5250 1550);
PAINT ORANGE (-5250 1550);
DISPLAY INVISIBLE (-5250 1550);
FORCEPROP 2 LAST CDS_SEC 1
J 0
(-5300 1700);
PAINT ORANGE (-5300 1700);
DISPLAY INVISIBLE (-5300 1700);
FORCEPROP 2 LAST SEC 1
J 0
(-5300 1750);
DISPLAY 0.680851 (-5300 1750);
PAINT MONO (-5300 1750);
DISPLAY INVISIBLE (-5300 1750);
FORCEPROP 1 LAST PATH I37
J 2
(-5300 1700);
DISPLAY 0.978723 (-5300 1700);
PAINT WHITE (-5300 1700);
DISPLAY INVISIBLE (-5300 1700);
FORCEPROP 2 LAST ROOM PVCCIN_CPU1_PWR_VR
J 0
(-5300 1700);
DISPLAY 1.361702 (-5300 1700);
PAINT ORANGE (-5300 1700);
DISPLAY INVISIBLE (-5300 1700);
FORCEPROP 2 LAST SEC_TYPE 0402V
J 0
(-5300 1750);
DISPLAY 1.021277 (-5300 1750);
PAINT ORANGE (-5300 1750);
DISPLAY INVISIBLE (-5300 1750);
FORCEADD CAP..1
R 2
(-5875 850);
FORCEPROP 1 LAST LOCATION C1D36
J 2
(-5925 950);
DISPLAY 0.617021 (-5925 950);
PAINT AQUA (-5925 950);
FORCEPROP 1 LASTPIN (-5875 950) $PN 1
J 2
(-5885 930);
DISPLAY 0.617021 (-5885 930);
PAINT ORANGE (-5885 930);
FORCEPROP 1 LAST MATERIAL X7R
J 2
(-5925 750);
DISPLAY 0.617021 (-5925 750);
PAINT SKYBLUE (-5925 750);
FORCEPROP 1 LASTPIN (-5875 750) $PN 2
J 2
(-5885 730);
DISPLAY 0.617021 (-5885 730);
PAINT ORANGE (-5885 730);
FORCEPROP 1 LAST PART_NUMBER A36096-104
J 2
(-5925 700);
DISPLAY 0.617021 (-5925 700);
PAINT BLUE (-5925 700);
FORCEPROP 1 LAST VALUE 0.220UF
J 2
(-5925 900);
DISPLAY 0.617021 (-5925 900);
PAINT SKYBLUE (-5925 900);
FORCEPROP 1 LAST VOLTAGE 16V
J 2
(-5925 850);
DISPLAY 0.617021 (-5925 850);
PAINT SKYBLUE (-5925 850);
FORCEPROP 1 LAST TOLERANCE 10%
J 2
(-5925 800);
DISPLAY 0.617021 (-5925 800);
PAINT SKYBLUE (-5925 800);
FORCEPROP 1 LAST PACK_TYPE 0402
J 2
(-5925 650);
DISPLAY 0.617021 (-5925 650);
PAINT SKYBLUE (-5925 650);
FORCEPROP 2 LAST SEC_TYPE 0402
J 0
(-5925 1050);
DISPLAY 1.021277 (-5925 1050);
PAINT ORANGE (-5925 1050);
DISPLAY INVISIBLE (-5925 1050);
FORCEPROP 0 LAST SPOF TRUE
J 0
(-5925 1050);
DISPLAY 1.021277 (-5925 1050);
PAINT ORANGE (-5925 1050);
DISPLAY INVISIBLE (-5925 1050);
FORCEPROP 2 LAST SEC 1
J 0
(-5925 1050);
DISPLAY 0.680851 (-5925 1050);
PAINT MONO (-5925 1050);
DISPLAY INVISIBLE (-5925 1050);
FORCEPROP 2 LAST NO_XNET_CONNECTION 1
J 0
(-5925 1050);
PAINT MONO (-5925 1050);
DISPLAY INVISIBLE (-5925 1050);
FORCEPROP 1 LAST PATH I38
J 2
(-5925 1000);
DISPLAY 0.978723 (-5925 1000);
PAINT WHITE (-5925 1000);
DISPLAY INVISIBLE (-5925 1000);
FORCEPROP 2 LAST ROOM PVCCIN_CPU1_PWR_VR
J 0
(-5925 1000);
DISPLAY 1.361702 (-5925 1000);
PAINT ORANGE (-5925 1000);
DISPLAY INVISIBLE (-5925 1000);
FORCEPROP 2 LAST CDS_LIB mstr_discrete
J 0
(-5875 850);
PAINT ORANGE (-5875 850);
DISPLAY INVISIBLE (-5875 850);
FORCEADD RES..1
(-5625 2000);
FORCEPROP 1 LASTPIN (-5525 2000) $PN 2
J 0
(-5563 2012);
DISPLAY 0.617021 (-5563 2012);
PAINT ORANGE (-5563 2012);
FORCEPROP 1 LAST VALUE 1.0
J 2
(-5725 1875);
DISPLAY 0.617021 (-5725 1875);
PAINT SKYBLUE (-5725 1875);
FORCEPROP 1 LASTPIN (-5725 2000) $PN 1
J 0
(-5713 2012);
DISPLAY 0.617021 (-5713 2012);
PAINT ORANGE (-5713 2012);
FORCEPROP 1 LAST WATTAGE 1/16W
J 2
(-5600 1825);
DISPLAY 0.617021 (-5600 1825);
PAINT SKYBLUE (-5600 1825);
FORCEPROP 1 LAST TOLERANCE 1%
J 0
(-5675 1875);
DISPLAY 0.617021 (-5675 1875);
PAINT SKYBLUE (-5675 1875);
FORCEPROP 1 LAST PART_NUMBER G21796-090
J 0
(-5750 1925);
DISPLAY 0.617021 (-5750 1925);
PAINT BLUE (-5750 1925);
FORCEPROP 1 LAST MATERIAL CHIP
J 0
(-5550 1825);
DISPLAY 0.617021 (-5550 1825);
PAINT SKYBLUE (-5550 1825);
FORCEPROP 1 LAST PACK_TYPE 0402
J 0
(-5575 1875);
DISPLAY 0.617021 (-5575 1875);
PAINT SKYBLUE (-5575 1875);
FORCEPROP 1 LAST LOCATION R9R11
J 0
(-5675 2050);
DISPLAY 0.617021 (-5675 2050);
PAINT AQUA (-5675 2050);
FORCEPROP 2 LAST CDS_LIB mstr_discrete
J 0
(-5625 2000);
PAINT ORANGE (-5625 2000);
DISPLAY INVISIBLE (-5625 2000);
FORCEPROP 2 LAST ROOM PVCCIN_CPU1_PWR_VR
J 0
(-5675 2100);
DISPLAY 1.361702 (-5675 2100);
PAINT ORANGE (-5675 2100);
DISPLAY INVISIBLE (-5675 2100);
FORCEPROP 1 LAST PATH I39
J 0
(-5675 2150);
DISPLAY 0.978723 (-5675 2150);
PAINT WHITE (-5675 2150);
DISPLAY INVISIBLE (-5675 2150);
FORCEPROP 2 LAST SEC 1
J 0
(-5675 2200);
DISPLAY 0.680851 (-5675 2200);
PAINT MONO (-5675 2200);
DISPLAY INVISIBLE (-5675 2200);
FORCEPROP 2 LAST SEC_TYPE 0402
J 0
(-5675 2200);
DISPLAY 1.021277 (-5675 2200);
PAINT ORANGE (-5675 2200);
DISPLAY INVISIBLE (-5675 2200);
FORCEADD CAP..1
(-5850 1500);
FORCEPROP 1 LASTPIN (-5850 1400) $PN 2
J 0
(-5840 1380);
DISPLAY 0.617021 (-5840 1380);
PAINT ORANGE (-5840 1380);
FORCEPROP 1 LAST MATERIAL X6S
J 0
(-5800 1400);
DISPLAY 0.617021 (-5800 1400);
PAINT SKYBLUE (-5800 1400);
FORCEPROP 1 LAST TOLERANCE 10%
J 0
(-5800 1450);
DISPLAY 0.617021 (-5800 1450);
PAINT SKYBLUE (-5800 1450);
FORCEPROP 1 LASTPIN (-5850 1600) $PN 1
J 0
(-5840 1580);
DISPLAY 0.617021 (-5840 1580);
PAINT ORANGE (-5840 1580);
FORCEPROP 1 LAST LOCATION C1E24
J 0
(-5800 1600);
DISPLAY 0.617021 (-5800 1600);
PAINT AQUA (-5800 1600);
FORCEPROP 1 LAST VALUE 1.0UF
J 0
(-5800 1550);
DISPLAY 0.617021 (-5800 1550);
PAINT SKYBLUE (-5800 1550);
FORCEPROP 1 LAST PART_NUMBER D97712-011
J 0
(-5800 1350);
DISPLAY 0.617021 (-5800 1350);
PAINT BLUE (-5800 1350);
FORCEPROP 1 LAST PACK_TYPE 0402
J 0
(-5800 1300);
DISPLAY 0.617021 (-5800 1300);
PAINT SKYBLUE (-5800 1300);
FORCEPROP 1 LAST VOLTAGE 16V
J 0
(-5800 1500);
DISPLAY 0.617021 (-5800 1500);
PAINT SKYBLUE (-5800 1500);
FORCEPROP 2 LAST CDS_LIB mstr_discrete
J 0
(-5850 1500);
PAINT ORANGE (-5850 1500);
DISPLAY INVISIBLE (-5850 1500);
FORCEPROP 2 LAST ROOM PVCCIN_CPU1_PWR_VR
J 0
(-5800 1650);
DISPLAY 1.361702 (-5800 1650);
PAINT ORANGE (-5800 1650);
DISPLAY INVISIBLE (-5800 1650);
FORCEPROP 1 LAST PATH I40
J 0
(-5800 1650);
DISPLAY 0.978723 (-5800 1650);
PAINT WHITE (-5800 1650);
DISPLAY INVISIBLE (-5800 1650);
FORCEPROP 2 LAST SEC_TYPE 0402
J 0
(-5800 1700);
DISPLAY 1.021277 (-5800 1700);
PAINT ORANGE (-5800 1700);
DISPLAY INVISIBLE (-5800 1700);
FORCEPROP 2 LAST SEC 1
J 0
(-5800 1700);
DISPLAY 0.680851 (-5800 1700);
PAINT MONO (-5800 1700);
DISPLAY INVISIBLE (-5800 1700);
FORCEADD CAP_A..1
(-6175 1500);
FORCEPROP 1 LAST TOLERANCE 10%
J 0
(-6125 1450);
DISPLAY 0.617021 (-6125 1450);
PAINT SKYBLUE (-6125 1450);
FORCEPROP 1 LASTPIN (-6175 1400) $PN 2
J 0
(-6165 1380);
DISPLAY 0.617021 (-6165 1380);
PAINT ORANGE (-6165 1380);
FORCEPROP 1 LASTPIN (-6175 1600) $PN 1
J 0
(-6165 1580);
DISPLAY 0.617021 (-6165 1580);
PAINT ORANGE (-6165 1580);
FORCEPROP 1 LAST VOLTAGE 16V
J 0
(-6125 1500);
DISPLAY 0.617021 (-6125 1500);
PAINT SKYBLUE (-6125 1500);
FORCEPROP 1 LAST LOCATION C1D34
J 0
(-6125 1600);
DISPLAY 0.617021 (-6125 1600);
PAINT AQUA (-6125 1600);
FORCEPROP 1 LAST VALUE 0.1UF
J 0
(-6125 1550);
DISPLAY 0.617021 (-6125 1550);
PAINT SKYBLUE (-6125 1550);
FORCEPROP 1 LAST PART_NUMBER A36096-030
J 0
(-6125 1350);
DISPLAY 0.617021 (-6125 1350);
PAINT BLUE (-6125 1350);
FORCEPROP 1 LAST MATERIAL X7R
J 0
(-6125 1400);
DISPLAY 0.617021 (-6125 1400);
PAINT SKYBLUE (-6125 1400);
FORCEPROP 1 LAST PACK_TYPE 0402V
J 0
(-6125 1300);
DISPLAY 0.617021 (-6125 1300);
PAINT SKYBLUE (-6125 1300);
FORCEPROP 2 LAST CDS_LIB dev_discrete
J 0
(-6175 1500);
PAINT ORANGE (-6175 1500);
DISPLAY INVISIBLE (-6175 1500);
FORCEPROP 1 LAST PATH I41
J 0
(-6125 1650);
DISPLAY 0.978723 (-6125 1650);
PAINT WHITE (-6125 1650);
DISPLAY INVISIBLE (-6125 1650);
FORCEPROP 2 LAST ROOM PVCCIN_CPU1_PWR_VR
J 0
(-6125 1650);
DISPLAY 1.361702 (-6125 1650);
PAINT ORANGE (-6125 1650);
DISPLAY INVISIBLE (-6125 1650);
FORCEPROP 2 LAST CDS_SEC 1
J 0
(-6125 1650);
PAINT ORANGE (-6125 1650);
DISPLAY INVISIBLE (-6125 1650);
FORCEPROP 2 LAST SEC 1
J 0
(-6125 1700);
DISPLAY 0.680851 (-6125 1700);
PAINT MONO (-6125 1700);
DISPLAY INVISIBLE (-6125 1700);
FORCEPROP 2 LAST SEC_TYPE 0402V
J 0
(-6125 1700);
DISPLAY 1.021277 (-6125 1700);
PAINT ORANGE (-6125 1700);
DISPLAY INVISIBLE (-6125 1700);
FORCEADD CAP..1
(-6450 1525);
FORCEPROP 1 LASTPIN (-6450 1425) $PN 2
J 0
(-6440 1405);
DISPLAY 0.617021 (-6440 1405);
PAINT ORANGE (-6440 1405);
FORCEPROP 1 LAST PACK_TYPE 0402
J 0
(-6400 1325);
DISPLAY 0.617021 (-6400 1325);
PAINT SKYBLUE (-6400 1325);
FORCEPROP 1 LAST MATERIAL X6S
J 0
(-6400 1425);
DISPLAY 0.617021 (-6400 1425);
PAINT SKYBLUE (-6400 1425);
FORCEPROP 1 LAST VOLTAGE 16V
J 0
(-6400 1525);
DISPLAY 0.617021 (-6400 1525);
PAINT SKYBLUE (-6400 1525);
FORCEPROP 1 LASTPIN (-6450 1625) $PN 1
J 0
(-6440 1605);
DISPLAY 0.617021 (-6440 1605);
PAINT ORANGE (-6440 1605);
FORCEPROP 1 LAST LOCATION C1D35
J 0
(-6400 1625);
DISPLAY 0.617021 (-6400 1625);
PAINT AQUA (-6400 1625);
FORCEPROP 1 LAST VALUE 1.0UF
J 0
(-6400 1575);
DISPLAY 0.617021 (-6400 1575);
PAINT SKYBLUE (-6400 1575);
FORCEPROP 1 LAST PART_NUMBER D97712-011
J 0
(-6400 1375);
DISPLAY 0.617021 (-6400 1375);
PAINT BLUE (-6400 1375);
FORCEPROP 1 LAST TOLERANCE 10%
J 0
(-6400 1475);
DISPLAY 0.617021 (-6400 1475);
PAINT SKYBLUE (-6400 1475);
FORCEPROP 2 LAST CDS_LIB mstr_discrete
J 0
(-6450 1525);
PAINT ORANGE (-6450 1525);
DISPLAY INVISIBLE (-6450 1525);
FORCEPROP 2 LAST SEC_TYPE 0402
J 0
(-6400 1725);
DISPLAY 1.021277 (-6400 1725);
PAINT ORANGE (-6400 1725);
DISPLAY INVISIBLE (-6400 1725);
FORCEPROP 2 LAST SEC 1
J 0
(-6400 1725);
DISPLAY 0.680851 (-6400 1725);
PAINT MONO (-6400 1725);
DISPLAY INVISIBLE (-6400 1725);
FORCEPROP 1 LAST PATH I42
J 0
(-6400 1675);
DISPLAY 0.978723 (-6400 1675);
PAINT WHITE (-6400 1675);
DISPLAY INVISIBLE (-6400 1675);
FORCEPROP 2 LAST ROOM PVCCIN_CPU1_PWR_VR
J 0
(-6400 1675);
DISPLAY 1.361702 (-6400 1675);
PAINT ORANGE (-6400 1675);
DISPLAY INVISIBLE (-6400 1675);
FORCEADD CAP..1
(-6875 4100);
FORCEPROP 1 LASTPIN (-6875 4000) $PN 2
J 0
(-6865 3980);
DISPLAY 0.617021 (-6865 3980);
PAINT ORANGE (-6865 3980);
FORCEPROP 1 LAST MATERIAL X6S
J 0
(-6825 4000);
DISPLAY 0.617021 (-6825 4000);
PAINT SKYBLUE (-6825 4000);
FORCEPROP 1 LAST PACK_TYPE 0805
J 0
(-6825 3900);
DISPLAY 0.617021 (-6825 3900);
PAINT SKYBLUE (-6825 3900);
FORCEPROP 1 LAST TOLERANCE 10%
J 0
(-6825 4050);
DISPLAY 0.617021 (-6825 4050);
PAINT SKYBLUE (-6825 4050);
FORCEPROP 1 LAST PART_NUMBER C95333-007
J 0
(-6825 3950);
DISPLAY 0.617021 (-6825 3950);
PAINT BLUE (-6825 3950);
FORCEPROP 1 LASTPIN (-6875 4200) $PN 1
J 0
(-6865 4180);
DISPLAY 0.617021 (-6865 4180);
PAINT ORANGE (-6865 4180);
FORCEPROP 1 LAST VOLTAGE 16V
J 0
(-6825 4100);
DISPLAY 0.617021 (-6825 4100);
PAINT SKYBLUE (-6825 4100);
FORCEPROP 1 LAST LOCATION C9R7
J 0
(-6825 4200);
DISPLAY 0.617021 (-6825 4200);
PAINT AQUA (-6825 4200);
FORCEPROP 1 LAST VALUE 10UF
J 0
(-6825 4150);
DISPLAY 0.617021 (-6825 4150);
PAINT SKYBLUE (-6825 4150);
FORCEPROP 2 LAST CDS_LIB mstr_discrete
J 0
(-6875 4100);
PAINT ORANGE (-6875 4100);
DISPLAY INVISIBLE (-6875 4100);
FORCEPROP 2 LAST CDS_LOCATION C9R7
J 0
(-6825 4200);
DISPLAY 0.617021 (-6825 4200);
PAINT AQUA (-6825 4200);
DISPLAY INVISIBLE (-6825 4200);
FORCEPROP 2 LAST ROOM PVCCIN_CPU1_PWR_VR
J 0
(-6825 4250);
DISPLAY 1.361702 (-6825 4250);
PAINT ORANGE (-6825 4250);
DISPLAY INVISIBLE (-6825 4250);
FORCEPROP 1 LAST PATH I43
J 0
(-6825 4250);
DISPLAY 0.978723 (-6825 4250);
PAINT WHITE (-6825 4250);
DISPLAY INVISIBLE (-6825 4250);
FORCEPROP 2 LAST SEC 1
J 0
(-6825 4300);
DISPLAY 0.680851 (-6825 4300);
PAINT MONO (-6825 4300);
DISPLAY INVISIBLE (-6825 4300);
FORCEPROP 2 LAST SEC_TYPE 0805
J 0
(-6825 4300);
DISPLAY 1.021277 (-6825 4300);
PAINT ORANGE (-6825 4300);
DISPLAY INVISIBLE (-6825 4300);
FORCEADD CAP..1
(-7175 4100);
FORCEPROP 1 LASTPIN (-7175 4000) $PN 2
J 0
(-7165 3980);
DISPLAY 0.617021 (-7165 3980);
PAINT ORANGE (-7165 3980);
FORCEPROP 1 LAST MATERIAL X6S
J 0
(-7125 4000);
DISPLAY 0.617021 (-7125 4000);
PAINT SKYBLUE (-7125 4000);
FORCEPROP 1 LAST PACK_TYPE 0805
J 0
(-7125 3900);
DISPLAY 0.617021 (-7125 3900);
PAINT SKYBLUE (-7125 3900);
FORCEPROP 1 LAST TOLERANCE 10%
J 0
(-7125 4050);
DISPLAY 0.617021 (-7125 4050);
PAINT SKYBLUE (-7125 4050);
FORCEPROP 1 LAST PART_NUMBER C95333-007
J 0
(-7125 3950);
DISPLAY 0.617021 (-7125 3950);
PAINT BLUE (-7125 3950);
FORCEPROP 1 LASTPIN (-7175 4200) $PN 1
J 0
(-7165 4180);
DISPLAY 0.617021 (-7165 4180);
PAINT ORANGE (-7165 4180);
FORCEPROP 1 LAST VOLTAGE 16V
J 0
(-7125 4100);
DISPLAY 0.617021 (-7125 4100);
PAINT SKYBLUE (-7125 4100);
FORCEPROP 1 LAST VALUE 10UF
J 0
(-7125 4150);
DISPLAY 0.617021 (-7125 4150);
PAINT SKYBLUE (-7125 4150);
FORCEPROP 1 LAST LOCATION C9R10
J 0
(-7125 4200);
DISPLAY 0.617021 (-7125 4200);
PAINT AQUA (-7125 4200);
FORCEPROP 2 LAST CDS_LIB mstr_discrete
J 0
(-7175 4100);
PAINT ORANGE (-7175 4100);
DISPLAY INVISIBLE (-7175 4100);
FORCEPROP 2 LAST ROOM PVCCIN_CPU1_PWR_VR
J 0
(-7125 4250);
DISPLAY 1.361702 (-7125 4250);
PAINT ORANGE (-7125 4250);
DISPLAY INVISIBLE (-7125 4250);
FORCEPROP 1 LAST PATH I44
J 0
(-7125 4250);
DISPLAY 0.978723 (-7125 4250);
PAINT WHITE (-7125 4250);
DISPLAY INVISIBLE (-7125 4250);
FORCEPROP 2 LAST CDS_LOCATION C9R10
J 0
(-7125 4200);
DISPLAY 0.617021 (-7125 4200);
PAINT AQUA (-7125 4200);
DISPLAY INVISIBLE (-7125 4200);
FORCEPROP 2 LAST SEC 1
J 0
(-7125 4300);
DISPLAY 0.680851 (-7125 4300);
PAINT MONO (-7125 4300);
DISPLAY INVISIBLE (-7125 4300);
FORCEPROP 2 LAST SEC_TYPE 0805
J 0
(-7125 4300);
DISPLAY 1.021277 (-7125 4300);
PAINT ORANGE (-7125 4300);
DISPLAY INVISIBLE (-7125 4300);
FORCEADD OFFPAGE..1
(-6775 3725);
FORCEPROP 2 LAST $XR0 206 
J 0
(-7027 3725);
DISPLAY 0.638298 (-7027 3725);
PAINT MONO (-7027 3725);
FORCEPROP 2 LASTPIN (-6725 3725) SIG_NAME VR_PVCCIN_CPU1_PWM1
J 0
(-6710 3735);
DISPLAY 0.617021 (-6710 3735);
PAINT ORANGE (-6710 3735);
FORCEPROP 2 LAST ROOM PVCCIN_CPU1_PWR_VR
J 0
(-7175 3800);
DISPLAY 1.936170 (-7175 3800);
PAINT ORANGE (-7175 3800);
DISPLAY INVISIBLE (-7175 3800);
FORCEPROP 2 LAST PATH I45
J 0
(-7020 3775);
DISPLAY 1.021277 (-7020 3775);
PAINT ORANGE (-7020 3775);
DISPLAY INVISIBLE (-7020 3775);
FORCEPROP 2 LAST BOM_COST PROC_VRD_VCCIN_CPU0
J 0
(-7025 3775);
DISPLAY 1.446809 (-7025 3775);
PAINT MONO (-7025 3775);
DISPLAY INVISIBLE (-7025 3775);
FORCEPROP 2 LAST CDS_LIB mstr_standard
J 0
(-6775 3725);
DISPLAY 1.936170 (-6775 3725);
PAINT ORANGE (-6775 3725);
DISPLAY INVISIBLE (-6775 3725);
FORCEPROP 1 LAST OFFPAGE TRUE
J 0
(-6450 3600);
DISPLAY 1.680851 (-6450 3600);
PAINT GREEN (-6450 3600);
DISPLAY INVISIBLE (-6450 3600);
FORCEPROP 1 LAST COMMENT_BODY TRUE
J 0
(-6650 3625);
DISPLAY 1.680851 (-6650 3625);
PAINT GREEN (-6650 3625);
DISPLAY INVISIBLE (-6650 3625);
FORCEADD CAP..1
(-7425 4100);
FORCEPROP 1 LASTPIN (-7425 4000) $PN 2
J 0
(-7415 3980);
DISPLAY 0.617021 (-7415 3980);
PAINT ORANGE (-7415 3980);
FORCEPROP 1 LAST MATERIAL X6S
J 0
(-7375 4000);
DISPLAY 0.617021 (-7375 4000);
PAINT SKYBLUE (-7375 4000);
FORCEPROP 1 LAST PACK_TYPE 0805
J 0
(-7375 3900);
DISPLAY 0.617021 (-7375 3900);
PAINT SKYBLUE (-7375 3900);
FORCEPROP 1 LAST TOLERANCE 10%
J 0
(-7375 4050);
DISPLAY 0.617021 (-7375 4050);
PAINT SKYBLUE (-7375 4050);
FORCEPROP 1 LAST PART_NUMBER C95333-007
J 0
(-7375 3950);
DISPLAY 0.617021 (-7375 3950);
PAINT BLUE (-7375 3950);
FORCEPROP 1 LASTPIN (-7425 4200) $PN 1
J 0
(-7415 4180);
DISPLAY 0.617021 (-7415 4180);
PAINT ORANGE (-7415 4180);
FORCEPROP 1 LAST VOLTAGE 16V
J 0
(-7375 4100);
DISPLAY 0.617021 (-7375 4100);
PAINT SKYBLUE (-7375 4100);
FORCEPROP 1 LAST VALUE 10UF
J 0
(-7375 4150);
DISPLAY 0.617021 (-7375 4150);
PAINT SKYBLUE (-7375 4150);
FORCEPROP 1 LAST LOCATION C9R11
J 0
(-7375 4200);
DISPLAY 0.617021 (-7375 4200);
PAINT AQUA (-7375 4200);
FORCEPROP 2 LAST CDS_LIB mstr_discrete
J 0
(-7425 4100);
PAINT ORANGE (-7425 4100);
DISPLAY INVISIBLE (-7425 4100);
FORCEPROP 2 LAST ROOM PVCCIN_CPU1_PWR_VR
J 0
(-7375 4250);
DISPLAY 1.361702 (-7375 4250);
PAINT ORANGE (-7375 4250);
DISPLAY INVISIBLE (-7375 4250);
FORCEPROP 1 LAST PATH I48
J 0
(-7375 4250);
DISPLAY 0.978723 (-7375 4250);
PAINT WHITE (-7375 4250);
DISPLAY INVISIBLE (-7375 4250);
FORCEPROP 2 LAST CDS_LOCATION C9R11
J 0
(-7375 4200);
DISPLAY 0.617021 (-7375 4200);
PAINT AQUA (-7375 4200);
DISPLAY INVISIBLE (-7375 4200);
FORCEPROP 2 LAST SEC 1
J 0
(-7375 4300);
DISPLAY 0.680851 (-7375 4300);
PAINT MONO (-7375 4300);
DISPLAY INVISIBLE (-7375 4300);
FORCEPROP 2 LAST SEC_TYPE 0805
J 0
(-7375 4300);
DISPLAY 1.021277 (-7375 4300);
PAINT ORANGE (-7375 4300);
DISPLAY INVISIBLE (-7375 4300);
FORCEADD GND..1
(-7525 3750);
FORCEPROP 3 LASTPIN (-7525 3800) SIG_NAME GND\g
J 0
(-7515 3810);
DISPLAY 0.659574 (-7515 3810);
PAINT MONO (-7515 3810);
DISPLAY INVISIBLE (-7515 3810);
FORCEPROP 2 LAST ROOM PVCCIN_CPU1_PWR_VR
J 0
(-8075 3825);
DISPLAY 1.936170 (-8075 3825);
PAINT ORANGE (-8075 3825);
DISPLAY INVISIBLE (-8075 3825);
FORCEPROP 2 LAST BOM_COST PROC_VRD_VCCIN_CPU0
J 0
(-7900 3825);
DISPLAY 1.446809 (-7900 3825);
PAINT MONO (-7900 3825);
DISPLAY INVISIBLE (-7900 3825);
FORCEPROP 1 LAST SIZE 1B
J 0
(-7450 3700);
DISPLAY 1.723404 (-7450 3700);
PAINT GREEN (-7450 3700);
DISPLAY INVISIBLE (-7450 3700);
FORCEPROP 2 LAST CDS_LIB mstr_symbols
J 0
(-7525 3750);
DISPLAY 1.936170 (-7525 3750);
PAINT ORANGE (-7525 3750);
DISPLAY INVISIBLE (-7525 3750);
FORCEPROP 1 LAST VOLTAGE 0
J 0
(-7525 3750);
PAINT SKYBLUE (-7525 3750);
DISPLAY INVISIBLE (-7525 3750);
FORCEPROP 1 LAST PATH I49
J 0
(-7450 3750);
DISPLAY 0.872340 (-7450 3750);
PAINT AQUA (-7450 3750);
DISPLAY INVISIBLE (-7450 3750);
FORCEPROP 1 LAST BODY_TYPE PLUMBING
J 0
(-7570 3707);
DISPLAY 0.340426 (-7570 3707);
PAINT GREEN (-7570 3707);
DISPLAY INVISIBLE (-7570 3707);
FORCEPROP 1 LAST HDL_POWER GND
J 0
(-7525 3900);
DISPLAY 1.723404 (-7525 3900);
PAINT GREEN (-7525 3900);
DISPLAY INVISIBLE (-7525 3900);
FORCEADD CAP..1
(-6800 1525);
FORCEPROP 1 LAST PART_NUMBER C95333-007
J 0
(-6750 1375);
DISPLAY 0.617021 (-6750 1375);
PAINT BLUE (-6750 1375);
FORCEPROP 1 LAST TOLERANCE 10%
J 0
(-6750 1475);
DISPLAY 0.617021 (-6750 1475);
PAINT SKYBLUE (-6750 1475);
FORCEPROP 1 LAST MATERIAL X6S
J 0
(-6750 1425);
DISPLAY 0.617021 (-6750 1425);
PAINT SKYBLUE (-6750 1425);
FORCEPROP 1 LASTPIN (-6800 1425) $PN 2
J 0
(-6790 1405);
DISPLAY 0.617021 (-6790 1405);
PAINT ORANGE (-6790 1405);
FORCEPROP 1 LAST VOLTAGE 16V
J 0
(-6750 1525);
DISPLAY 0.617021 (-6750 1525);
PAINT SKYBLUE (-6750 1525);
FORCEPROP 1 LASTPIN (-6800 1625) $PN 1
J 0
(-6790 1605);
DISPLAY 0.617021 (-6790 1605);
PAINT ORANGE (-6790 1605);
FORCEPROP 1 LAST PACK_TYPE 0805
J 0
(-6750 1325);
DISPLAY 0.617021 (-6750 1325);
PAINT SKYBLUE (-6750 1325);
FORCEPROP 1 LAST VALUE 10UF
J 0
(-6750 1575);
DISPLAY 0.617021 (-6750 1575);
PAINT SKYBLUE (-6750 1575);
FORCEPROP 1 LAST LOCATION C9P22
J 0
(-6750 1625);
DISPLAY 0.617021 (-6750 1625);
PAINT AQUA (-6750 1625);
FORCEPROP 2 LAST CDS_LIB mstr_discrete
J 0
(-6800 1525);
PAINT ORANGE (-6800 1525);
DISPLAY INVISIBLE (-6800 1525);
FORCEPROP 2 LAST ROOM PVCCIN_CPU1_PWR_VR
J 0
(-6750 1675);
DISPLAY 1.361702 (-6750 1675);
PAINT ORANGE (-6750 1675);
DISPLAY INVISIBLE (-6750 1675);
FORCEPROP 1 LAST PATH I50
J 0
(-6750 1675);
DISPLAY 0.978723 (-6750 1675);
PAINT WHITE (-6750 1675);
DISPLAY INVISIBLE (-6750 1675);
FORCEPROP 2 LAST CDS_LOCATION C9P22
J 0
(-6750 1625);
DISPLAY 0.617021 (-6750 1625);
PAINT AQUA (-6750 1625);
DISPLAY INVISIBLE (-6750 1625);
FORCEPROP 2 LAST SEC 1
J 0
(-6750 1725);
DISPLAY 0.680851 (-6750 1725);
PAINT MONO (-6750 1725);
DISPLAY INVISIBLE (-6750 1725);
FORCEPROP 2 LAST SEC_TYPE 0805
J 0
(-6750 1725);
DISPLAY 1.021277 (-6750 1725);
PAINT ORANGE (-6750 1725);
DISPLAY INVISIBLE (-6750 1725);
FORCEADD CAP..1
(-7125 1525);
FORCEPROP 1 LASTPIN (-7125 1425) $PN 2
J 0
(-7115 1405);
DISPLAY 0.617021 (-7115 1405);
PAINT ORANGE (-7115 1405);
FORCEPROP 1 LAST MATERIAL X6S
J 0
(-7075 1425);
DISPLAY 0.617021 (-7075 1425);
PAINT SKYBLUE (-7075 1425);
FORCEPROP 1 LAST PACK_TYPE 0805
J 0
(-7075 1325);
DISPLAY 0.617021 (-7075 1325);
PAINT SKYBLUE (-7075 1325);
FORCEPROP 1 LAST TOLERANCE 10%
J 0
(-7075 1475);
DISPLAY 0.617021 (-7075 1475);
PAINT SKYBLUE (-7075 1475);
FORCEPROP 1 LAST PART_NUMBER C95333-007
J 0
(-7075 1375);
DISPLAY 0.617021 (-7075 1375);
PAINT BLUE (-7075 1375);
FORCEPROP 1 LAST VOLTAGE 16V
J 0
(-7075 1525);
DISPLAY 0.617021 (-7075 1525);
PAINT SKYBLUE (-7075 1525);
FORCEPROP 1 LASTPIN (-7125 1625) $PN 1
J 0
(-7115 1605);
DISPLAY 0.617021 (-7115 1605);
PAINT ORANGE (-7115 1605);
FORCEPROP 1 LAST LOCATION C9P25
J 0
(-7075 1625);
DISPLAY 0.617021 (-7075 1625);
PAINT AQUA (-7075 1625);
FORCEPROP 1 LAST VALUE 10UF
J 0
(-7075 1575);
DISPLAY 0.617021 (-7075 1575);
PAINT SKYBLUE (-7075 1575);
FORCEPROP 2 LAST CDS_LIB mstr_discrete
J 0
(-7125 1525);
PAINT ORANGE (-7125 1525);
DISPLAY INVISIBLE (-7125 1525);
FORCEPROP 2 LAST ROOM PVCCIN_CPU1_PWR_VR
J 0
(-7075 1675);
DISPLAY 1.361702 (-7075 1675);
PAINT ORANGE (-7075 1675);
DISPLAY INVISIBLE (-7075 1675);
FORCEPROP 1 LAST PATH I51
J 0
(-7075 1675);
DISPLAY 0.978723 (-7075 1675);
PAINT WHITE (-7075 1675);
DISPLAY INVISIBLE (-7075 1675);
FORCEPROP 2 LAST SEC 1
J 0
(-7075 1725);
DISPLAY 0.680851 (-7075 1725);
PAINT MONO (-7075 1725);
DISPLAY INVISIBLE (-7075 1725);
FORCEPROP 2 LAST SEC_TYPE 0805
J 0
(-7075 1725);
DISPLAY 1.021277 (-7075 1725);
PAINT ORANGE (-7075 1725);
DISPLAY INVISIBLE (-7075 1725);
FORCEADD OFFPAGE..1
(-6950 1125);
FORCEPROP 2 LAST $XR0 206 
J 0
(-7202 1125);
DISPLAY 0.638298 (-7202 1125);
PAINT MONO (-7202 1125);
FORCEPROP 2 LAST PATH I52
J 0
(-7195 1175);
DISPLAY 1.021277 (-7195 1175);
PAINT ORANGE (-7195 1175);
DISPLAY INVISIBLE (-7195 1175);
FORCEPROP 2 LAST ROOM PVCCIN_CPU1_PWR_VR
J 0
(-7350 1200);
DISPLAY 1.936170 (-7350 1200);
PAINT ORANGE (-7350 1200);
DISPLAY INVISIBLE (-7350 1200);
FORCEPROP 2 LAST BOM_COST PROC_VRD_VCCIN_CPU0
J 0
(-7200 1175);
DISPLAY 1.446809 (-7200 1175);
PAINT MONO (-7200 1175);
DISPLAY INVISIBLE (-7200 1175);
FORCEPROP 2 LAST CDS_LIB mstr_standard
J 0
(-6950 1125);
PAINT ORANGE (-6950 1125);
DISPLAY INVISIBLE (-6950 1125);
FORCEPROP 1 LAST OFFPAGE TRUE
J 0
(-6625 1000);
DISPLAY 1.680851 (-6625 1000);
PAINT GREEN (-6625 1000);
DISPLAY INVISIBLE (-6625 1000);
FORCEPROP 1 LAST COMMENT_BODY TRUE
J 0
(-6825 1025);
DISPLAY 1.680851 (-6825 1025);
PAINT GREEN (-6825 1025);
DISPLAY INVISIBLE (-6825 1025);
FORCEADD VCC_CORE..1
(-7500 1825);
FORCEPROP 3 LASTPIN (-7500 1775) SIG_NAME VR_FET_SW_P12V_STBY_PVCCIN_CPU1\g
J 0
(-7490 1785);
DISPLAY 0.659574 (-7490 1785);
PAINT MONO (-7490 1785);
DISPLAY INVISIBLE (-7490 1785);
FORCEPROP 1 LAST HDL_POWER VR_FET_SW_P12V_STBY_PVCCIN_CPU1
J 1
(-7475 1875);
DISPLAY 0.617021 (-7475 1875);
PAINT GREEN (-7475 1875);
FORCEPROP 2 LAST CDS_LIB mstr_symbols
J 0
(-7500 1825);
PAINT ORANGE (-7500 1825);
DISPLAY INVISIBLE (-7500 1825);
FORCEPROP 1 LAST PATH I53
J 0
(-7450 1850);
DISPLAY 0.872340 (-7450 1850);
PAINT AQUA (-7450 1850);
DISPLAY INVISIBLE (-7450 1850);
FORCEADD CAP..1
(-7450 1525);
FORCEPROP 1 LASTPIN (-7450 1425) $PN 2
J 0
(-7440 1405);
DISPLAY 0.617021 (-7440 1405);
PAINT ORANGE (-7440 1405);
FORCEPROP 1 LAST MATERIAL X6S
J 0
(-7400 1425);
DISPLAY 0.617021 (-7400 1425);
PAINT SKYBLUE (-7400 1425);
FORCEPROP 1 LAST PACK_TYPE 0805
J 0
(-7400 1325);
DISPLAY 0.617021 (-7400 1325);
PAINT SKYBLUE (-7400 1325);
FORCEPROP 1 LAST TOLERANCE 10%
J 0
(-7400 1475);
DISPLAY 0.617021 (-7400 1475);
PAINT SKYBLUE (-7400 1475);
FORCEPROP 1 LAST VOLTAGE 16V
J 0
(-7400 1525);
DISPLAY 0.617021 (-7400 1525);
PAINT SKYBLUE (-7400 1525);
FORCEPROP 1 LASTPIN (-7450 1625) $PN 1
J 0
(-7440 1605);
DISPLAY 0.617021 (-7440 1605);
PAINT ORANGE (-7440 1605);
FORCEPROP 1 LAST VALUE 10UF
J 0
(-7400 1575);
DISPLAY 0.617021 (-7400 1575);
PAINT SKYBLUE (-7400 1575);
FORCEPROP 1 LAST LOCATION C9P26
J 0
(-7400 1625);
DISPLAY 0.617021 (-7400 1625);
PAINT AQUA (-7400 1625);
FORCEPROP 1 LAST PART_NUMBER C95333-007
J 0
(-7400 1375);
DISPLAY 0.617021 (-7400 1375);
PAINT BLUE (-7400 1375);
FORCEPROP 2 LAST CDS_LIB mstr_discrete
J 0
(-7450 1525);
PAINT ORANGE (-7450 1525);
DISPLAY INVISIBLE (-7450 1525);
FORCEPROP 2 LAST SEC_TYPE 0805
J 0
(-7400 1725);
DISPLAY 1.021277 (-7400 1725);
PAINT ORANGE (-7400 1725);
DISPLAY INVISIBLE (-7400 1725);
FORCEPROP 2 LAST SEC 1
J 0
(-7400 1725);
DISPLAY 0.680851 (-7400 1725);
PAINT MONO (-7400 1725);
DISPLAY INVISIBLE (-7400 1725);
FORCEPROP 1 LAST PATH I54
J 0
(-7400 1675);
DISPLAY 0.978723 (-7400 1675);
PAINT WHITE (-7400 1675);
DISPLAY INVISIBLE (-7400 1675);
FORCEPROP 2 LAST ROOM PVCCIN_CPU1_PWR_VR
J 0
(-7400 1675);
DISPLAY 1.361702 (-7400 1675);
PAINT ORANGE (-7400 1675);
DISPLAY INVISIBLE (-7400 1675);
FORCEADD GND..1
(-7500 1175);
FORCEPROP 3 LASTPIN (-7500 1225) SIG_NAME GND\g
J 0
(-7490 1235);
DISPLAY 0.659574 (-7490 1235);
PAINT MONO (-7490 1235);
DISPLAY INVISIBLE (-7490 1235);
FORCEPROP 2 LAST ROOM PVCCIN_CPU1_PWR_VR
J 0
(-8050 1250);
DISPLAY 1.936170 (-8050 1250);
PAINT ORANGE (-8050 1250);
DISPLAY INVISIBLE (-8050 1250);
FORCEPROP 2 LAST BOM_COST PROC_VRD_VCCIN_CPU0
J 0
(-7875 1250);
DISPLAY 1.446809 (-7875 1250);
PAINT MONO (-7875 1250);
DISPLAY INVISIBLE (-7875 1250);
FORCEPROP 1 LAST SIZE 1B
J 0
(-7425 1125);
DISPLAY 1.723404 (-7425 1125);
PAINT GREEN (-7425 1125);
DISPLAY INVISIBLE (-7425 1125);
FORCEPROP 1 LAST VOLTAGE 0
J 0
(-7500 1175);
PAINT SKYBLUE (-7500 1175);
DISPLAY INVISIBLE (-7500 1175);
FORCEPROP 2 LAST CDS_LIB mstr_symbols
J 0
(-7500 1175);
PAINT ORANGE (-7500 1175);
DISPLAY INVISIBLE (-7500 1175);
FORCEPROP 1 LAST PATH I55
J 0
(-7425 1175);
DISPLAY 0.872340 (-7425 1175);
PAINT AQUA (-7425 1175);
DISPLAY INVISIBLE (-7425 1175);
FORCEPROP 1 LAST BODY_TYPE PLUMBING
J 0
(-7545 1132);
DISPLAY 0.340426 (-7545 1132);
PAINT GREEN (-7545 1132);
DISPLAY INVISIBLE (-7545 1132);
FORCEPROP 1 LAST HDL_POWER GND
J 0
(-7500 1325);
DISPLAY 1.723404 (-7500 1325);
PAINT GREEN (-7500 1325);
DISPLAY INVISIBLE (-7500 1325);
FORCEADD P5V_STBY..1
(-4550 4775);
FORCEPROP 3 LASTPIN (-4550 4725) SIG_NAME P5V_STBY\g
J 0
(-4540 4735);
DISPLAY 0.659574 (-4540 4735);
PAINT MONO (-4540 4735);
DISPLAY INVISIBLE (-4540 4735);
FORCEPROP 1 LAST VOLTAGE 5.0V
J 0
(-4595 4732);
DISPLAY 0.340426 (-4595 4732);
PAINT SKYBLUE (-4595 4732);
DISPLAY INVISIBLE (-4595 4732);
FORCEPROP 1 LAST SIZE 1B
J 0
(-4505 4797);
DISPLAY 0.340426 (-4505 4797);
PAINT GREEN (-4505 4797);
DISPLAY INVISIBLE (-4505 4797);
FORCEPROP 2 LAST CDS_LIB mstr_symbols
J 0
(-4550 4775);
PAINT ORANGE (-4550 4775);
DISPLAY INVISIBLE (-4550 4775);
FORCEPROP 1 LAST PATH I56
J 0
(-4505 4777);
DISPLAY 0.340426 (-4505 4777);
PAINT GREEN (-4505 4777);
DISPLAY INVISIBLE (-4505 4777);
FORCEPROP 1 LAST BODY_TYPE PLUMBING
J 0
(-4595 4732);
DISPLAY 0.340426 (-4595 4732);
PAINT GREEN (-4595 4732);
DISPLAY INVISIBLE (-4595 4732);
FORCEPROP 1 LAST HDL_POWER P5V_STBY
J 0
(-4850 4650);
DISPLAY 0.872340 (-4850 4650);
PAINT ORANGE (-4850 4650);
DISPLAY INVISIBLE (-4850 4650);
FORCEADD P5V_STBY..1
(-5150 2175);
FORCEPROP 3 LASTPIN (-5150 2125) SIG_NAME P5V_STBY\g
J 0
(-5140 2135);
DISPLAY 0.659574 (-5140 2135);
PAINT MONO (-5140 2135);
DISPLAY INVISIBLE (-5140 2135);
FORCEPROP 2 LAST CDS_LIB mstr_symbols
J 0
(-5150 2175);
PAINT ORANGE (-5150 2175);
DISPLAY INVISIBLE (-5150 2175);
FORCEPROP 1 LAST VOLTAGE 5.0V
J 0
(-5195 2132);
DISPLAY 0.340426 (-5195 2132);
PAINT SKYBLUE (-5195 2132);
DISPLAY INVISIBLE (-5195 2132);
FORCEPROP 1 LAST PATH I57
J 0
(-5105 2177);
DISPLAY 0.340426 (-5105 2177);
PAINT GREEN (-5105 2177);
DISPLAY INVISIBLE (-5105 2177);
FORCEPROP 1 LAST SIZE 1B
J 0
(-5105 2197);
DISPLAY 0.340426 (-5105 2197);
PAINT GREEN (-5105 2197);
DISPLAY INVISIBLE (-5105 2197);
FORCEPROP 1 LAST BODY_TYPE PLUMBING
J 0
(-5195 2132);
DISPLAY 0.340426 (-5195 2132);
PAINT GREEN (-5195 2132);
DISPLAY INVISIBLE (-5195 2132);
FORCEPROP 1 LAST HDL_POWER P5V_STBY
J 0
(-5450 2050);
DISPLAY 0.872340 (-5450 2050);
PAINT ORANGE (-5450 2050);
DISPLAY INVISIBLE (-5450 2050);
FORCEADD CAP_A..1
(-975 3350);
FORCEPROP 1 LAST PACK_TYPE 0603V
J 0
(-925 3150);
DISPLAY 0.617021 (-925 3150);
PAINT SKYBLUE (-925 3150);
FORCEPROP 1 LAST PART_NUMBER E15431-004
J 0
(-925 3200);
DISPLAY 0.617021 (-925 3200);
PAINT BLUE (-925 3200);
FORCEPROP 1 LAST VALUE 22.0UF
J 0
(-925 3400);
DISPLAY 0.617021 (-925 3400);
PAINT SKYBLUE (-925 3400);
FORCEPROP 1 LASTPIN (-975 3250) $PN 2
J 0
(-965 3230);
DISPLAY 0.617021 (-965 3230);
PAINT ORANGE (-965 3230);
FORCEPROP 1 LAST TOLERANCE 20%
J 0
(-925 3300);
DISPLAY 0.617021 (-925 3300);
PAINT SKYBLUE (-925 3300);
FORCEPROP 1 LAST MATERIAL X6S
J 0
(-925 3250);
DISPLAY 0.617021 (-925 3250);
PAINT SKYBLUE (-925 3250);
FORCEPROP 1 LASTPIN (-975 3450) $PN 1
J 0
(-965 3430);
DISPLAY 0.617021 (-965 3430);
PAINT ORANGE (-965 3430);
FORCEPROP 1 LAST LOCATION C1E9
J 0
(-925 3450);
DISPLAY 0.617021 (-925 3450);
PAINT AQUA (-925 3450);
FORCEPROP 1 LAST VOLTAGE 4V
J 0
(-925 3350);
DISPLAY 0.617021 (-925 3350);
PAINT SKYBLUE (-925 3350);
FORCEPROP 2 LAST CDS_LIB dev_discrete
J 0
(-975 3350);
PAINT ORANGE (-975 3350);
DISPLAY INVISIBLE (-975 3350);
FORCEPROP 2 LAST CDS_LOCATION C1E9
J 0
(-925 3450);
DISPLAY 0.617021 (-925 3450);
PAINT AQUA (-925 3450);
DISPLAY INVISIBLE (-925 3450);
FORCEPROP 1 LAST PATH I58
J 0
(-925 3500);
DISPLAY 0.978723 (-925 3500);
PAINT WHITE (-925 3500);
DISPLAY INVISIBLE (-925 3500);
FORCEPROP 2 LAST SEC 1
J 0
(-925 3550);
DISPLAY 0.680851 (-925 3550);
PAINT MONO (-925 3550);
DISPLAY INVISIBLE (-925 3550);
FORCEPROP 2 LAST CDS_SEC 1
J 0
(-925 3500);
PAINT ORANGE (-925 3500);
DISPLAY INVISIBLE (-925 3500);
FORCEPROP 2 LAST SEC_TYPE 0603V
J 0
(-925 3550);
DISPLAY 1.021277 (-925 3550);
PAINT ORANGE (-925 3550);
DISPLAY INVISIBLE (-925 3550);
FORCEADD CAP_A..1
(-1075 775);
FORCEPROP 1 LAST VALUE 22.0UF
J 0
(-1025 825);
DISPLAY 0.617021 (-1025 825);
PAINT SKYBLUE (-1025 825);
FORCEPROP 1 LAST VOLTAGE 4V
J 0
(-1025 775);
DISPLAY 0.617021 (-1025 775);
PAINT SKYBLUE (-1025 775);
FORCEPROP 1 LASTPIN (-1075 875) $PN 1
J 0
(-1065 855);
DISPLAY 0.617021 (-1065 855);
PAINT ORANGE (-1065 855);
FORCEPROP 1 LAST MATERIAL X6S
J 0
(-1025 675);
DISPLAY 0.617021 (-1025 675);
PAINT SKYBLUE (-1025 675);
FORCEPROP 1 LAST TOLERANCE 20%
J 0
(-1025 725);
DISPLAY 0.617021 (-1025 725);
PAINT SKYBLUE (-1025 725);
FORCEPROP 1 LAST PACK_TYPE 0603V
J 0
(-1025 575);
DISPLAY 0.617021 (-1025 575);
PAINT SKYBLUE (-1025 575);
FORCEPROP 1 LAST PART_NUMBER E15431-004
J 0
(-1025 625);
DISPLAY 0.617021 (-1025 625);
PAINT BLUE (-1025 625);
FORCEPROP 1 LASTPIN (-1075 675) $PN 2
J 0
(-1065 655);
DISPLAY 0.617021 (-1065 655);
PAINT ORANGE (-1065 655);
FORCEPROP 1 LAST LOCATION C9P3
J 0
(-1025 875);
DISPLAY 0.617021 (-1025 875);
PAINT AQUA (-1025 875);
FORCEPROP 2 LAST CDS_LIB dev_discrete
J 0
(-1075 775);
PAINT ORANGE (-1075 775);
DISPLAY INVISIBLE (-1075 775);
FORCEPROP 2 LAST CDS_LOCATION C9P3
J 0
(-1025 875);
DISPLAY 0.617021 (-1025 875);
PAINT AQUA (-1025 875);
DISPLAY INVISIBLE (-1025 875);
FORCEPROP 1 LAST PATH I59
J 0
(-1025 925);
DISPLAY 0.978723 (-1025 925);
PAINT WHITE (-1025 925);
DISPLAY INVISIBLE (-1025 925);
FORCEPROP 2 LAST SEC 1
J 0
(-1025 975);
DISPLAY 0.680851 (-1025 975);
PAINT MONO (-1025 975);
DISPLAY INVISIBLE (-1025 975);
FORCEPROP 2 LAST SEC_TYPE 0603V
J 0
(-1025 975);
DISPLAY 1.021277 (-1025 975);
PAINT ORANGE (-1025 975);
DISPLAY INVISIBLE (-1025 975);
FORCEPROP 2 LAST CDS_SEC 1
J 0
(-1025 925);
PAINT ORANGE (-1025 925);
DISPLAY INVISIBLE (-1025 925);
FORCEADD OFFPAGE..2
(-1775 4375);
FORCEPROP 2 LAST $XR0 206 
J 0
(-1586 4375);
DISPLAY 0.638298 (-1586 4375);
PAINT MONO (-1586 4375);
FORCEPROP 2 LAST ROOM PVCCIN_CPU1_PWR_VR
J 0
(-2175 4450);
DISPLAY 1.936170 (-2175 4450);
PAINT ORANGE (-2175 4450);
DISPLAY INVISIBLE (-2175 4450);
FORCEPROP 2 LAST PATH I62
J 0
(-1600 4450);
DISPLAY 1.021277 (-1600 4450);
PAINT ORANGE (-1600 4450);
DISPLAY INVISIBLE (-1600 4450);
FORCEPROP 2 LAST BOM_COST PROC_VRD_VCCIN_CPU0
J 0
(-1575 4425);
DISPLAY 1.446809 (-1575 4425);
PAINT MONO (-1575 4425);
DISPLAY INVISIBLE (-1575 4425);
FORCEPROP 2 LAST CDS_LIB mstr_standard
J 0
(-1775 4375);
PAINT ORANGE (-1775 4375);
DISPLAY INVISIBLE (-1775 4375);
FORCEPROP 1 LAST OFFPAGE TRUE
J 0
(-1450 4250);
DISPLAY 1.723404 (-1450 4250);
PAINT GREEN (-1450 4250);
DISPLAY INVISIBLE (-1450 4250);
FORCEPROP 1 LAST COMMENT_BODY TRUE
J 0
(-1820 4280);
DISPLAY 1.723404 (-1820 4280);
PAINT GREEN (-1820 4280);
DISPLAY INVISIBLE (-1820 4280);
FORCEADD OFFPAGE..2
(-1275 1775);
FORCEPROP 2 LAST $XR0 206 
J 0
(-1086 1775);
DISPLAY 0.638298 (-1086 1775);
PAINT MONO (-1086 1775);
FORCEPROP 2 LAST ROOM PVCCIN_CPU1_PWR_VR
J 0
(-1675 1850);
DISPLAY 1.936170 (-1675 1850);
PAINT ORANGE (-1675 1850);
DISPLAY INVISIBLE (-1675 1850);
FORCEPROP 2 LAST CDS_LIB mstr_standard
J 0
(-1275 1775);
PAINT ORANGE (-1275 1775);
DISPLAY INVISIBLE (-1275 1775);
FORCEPROP 2 LAST PATH I64
J 0
(-1100 1850);
DISPLAY 1.021277 (-1100 1850);
PAINT ORANGE (-1100 1850);
DISPLAY INVISIBLE (-1100 1850);
FORCEPROP 2 LAST BOM_COST PROC_VRD_VCCIN_CPU0
J 0
(-1075 1825);
DISPLAY 1.446809 (-1075 1825);
PAINT MONO (-1075 1825);
DISPLAY INVISIBLE (-1075 1825);
FORCEPROP 1 LAST OFFPAGE TRUE
J 0
(-950 1650);
DISPLAY 1.723404 (-950 1650);
PAINT GREEN (-950 1650);
DISPLAY INVISIBLE (-950 1650);
FORCEPROP 1 LAST COMMENT_BODY TRUE
J 0
(-1320 1680);
DISPLAY 1.723404 (-1320 1680);
PAINT GREEN (-1320 1680);
DISPLAY INVISIBLE (-1320 1680);
FORCEADD RES..2
(-1025 1400);
FORCEPROP 1 LAST PACK_TYPE 0402
J 0
(-985 1225);
DISPLAY 0.617021 (-985 1225);
PAINT SKYBLUE (-985 1225);
FORCEPROP 1 LASTPIN (-1025 1300) $PN 2
J 0
(-1020 1310);
DISPLAY 0.617021 (-1020 1310);
PAINT ORANGE (-1020 1310);
FORCEPROP 1 LASTPIN (-1025 1500) $PN 1
J 0
(-1020 1462);
DISPLAY 0.617021 (-1020 1462);
PAINT ORANGE (-1020 1462);
FORCEPROP 1 LAST TOLERANCE 1%
J 0
(-980 1425);
DISPLAY 0.617021 (-980 1425);
PAINT SKYBLUE (-980 1425);
FORCEPROP 1 LAST WATTAGE 1/16W
J 0
(-985 1375);
DISPLAY 0.617021 (-985 1375);
PAINT SKYBLUE (-985 1375);
FORCEPROP 1 LAST VALUE 68.1K
J 0
(-980 1475);
DISPLAY 0.617021 (-980 1475);
PAINT SKYBLUE (-980 1475);
FORCEPROP 1 LAST MATERIAL EMPTY
J 0
(-985 1325);
DISPLAY 0.617021 (-985 1325);
PAINT RED (-985 1325);
FORCEPROP 1 LAST PART_NUMBER G21796-187
J 0
(-985 1275);
DISPLAY 0.617021 (-985 1275);
PAINT BLUE (-985 1275);
FORCEPROP 1 LAST LOCATION R1E13
J 0
(-980 1525);
DISPLAY 0.617021 (-980 1525);
PAINT AQUA (-980 1525);
FORCEPROP 2 LAST CDS_LIB mstr_discrete
J 0
(-1025 1400);
PAINT ORANGE (-1025 1400);
DISPLAY INVISIBLE (-1025 1400);
FORCEPROP 1 LAST PATH I67
J 0
(-975 1575);
DISPLAY 0.978723 (-975 1575);
PAINT WHITE (-975 1575);
DISPLAY INVISIBLE (-975 1575);
FORCEPROP 2 LAST $SEC 1
J 0
(-975 1625);
PAINT MONO (-975 1625);
DISPLAY INVISIBLE (-975 1625);
FORCEPROP 2 LAST CDS_SEC 1
J 0
(-975 1625);
PAINT MONO (-975 1625);
DISPLAY INVISIBLE (-975 1625);
FORCEADD RES..2
(-550 4025);
FORCEPROP 1 LASTPIN (-550 3925) $PN 2
J 0
(-545 3935);
DISPLAY 0.617021 (-545 3935);
PAINT ORANGE (-545 3935);
FORCEPROP 1 LAST PACK_TYPE 0402
J 0
(-510 3850);
DISPLAY 0.617021 (-510 3850);
PAINT SKYBLUE (-510 3850);
FORCEPROP 1 LAST TOLERANCE 1%
J 0
(-505 4050);
DISPLAY 0.617021 (-505 4050);
PAINT SKYBLUE (-505 4050);
FORCEPROP 1 LAST WATTAGE 1/16W
J 0
(-510 4000);
DISPLAY 0.617021 (-510 4000);
PAINT SKYBLUE (-510 4000);
FORCEPROP 1 LAST MATERIAL EMPTY
J 0
(-510 3950);
DISPLAY 0.617021 (-510 3950);
PAINT RED (-510 3950);
FORCEPROP 1 LAST PART_NUMBER G21796-187
J 0
(-510 3900);
DISPLAY 0.617021 (-510 3900);
PAINT BLUE (-510 3900);
FORCEPROP 1 LASTPIN (-550 4125) $PN 1
J 0
(-545 4087);
DISPLAY 0.617021 (-545 4087);
PAINT ORANGE (-545 4087);
FORCEPROP 1 LAST VALUE 68.1K
J 0
(-505 4100);
DISPLAY 0.617021 (-505 4100);
PAINT SKYBLUE (-505 4100);
FORCEPROP 1 LAST LOCATION R1E14
J 0
(-505 4150);
DISPLAY 0.617021 (-505 4150);
PAINT AQUA (-505 4150);
FORCEPROP 2 LAST CDS_LIB mstr_discrete
J 0
(-550 4025);
PAINT ORANGE (-550 4025);
DISPLAY INVISIBLE (-550 4025);
FORCEPROP 1 LAST PATH I68
J 0
(-500 4200);
DISPLAY 0.978723 (-500 4200);
PAINT WHITE (-500 4200);
DISPLAY INVISIBLE (-500 4200);
FORCEPROP 2 LAST $SEC 1
J 0
(-500 4250);
PAINT MONO (-500 4250);
DISPLAY INVISIBLE (-500 4250);
FORCEPROP 2 LAST CDS_SEC 1
J 0
(-500 4250);
PAINT MONO (-500 4250);
DISPLAY INVISIBLE (-500 4250);
FORCEADD GND..1
(-550 3825);
FORCEPROP 3 LASTPIN (-550 3875) SIG_NAME GND\g
J 0
(-540 3885);
DISPLAY 0.659574 (-540 3885);
PAINT MONO (-540 3885);
DISPLAY INVISIBLE (-540 3885);
FORCEPROP 2 LAST ROOM PVCCIN_CPU1_PWR_VR
J 0
(-1100 3900);
DISPLAY 1.936170 (-1100 3900);
PAINT ORANGE (-1100 3900);
DISPLAY INVISIBLE (-1100 3900);
FORCEPROP 2 LAST BOM_COST PROC_VRD_VCCIN_CPU0
J 0
(-925 3900);
DISPLAY 1.446809 (-925 3900);
PAINT MONO (-925 3900);
DISPLAY INVISIBLE (-925 3900);
FORCEPROP 2 LAST CDS_LIB mstr_symbols
J 0
(-550 3825);
PAINT ORANGE (-550 3825);
DISPLAY INVISIBLE (-550 3825);
FORCEPROP 1 LAST VOLTAGE 0
J 0
(-550 3825);
PAINT SKYBLUE (-550 3825);
DISPLAY INVISIBLE (-550 3825);
FORCEPROP 1 LAST PATH I69
J 0
(-475 3825);
DISPLAY 0.872340 (-475 3825);
PAINT AQUA (-475 3825);
DISPLAY INVISIBLE (-475 3825);
FORCEPROP 1 LAST SIZE 1B
J 0
(-475 3775);
DISPLAY 1.723404 (-475 3775);
PAINT GREEN (-475 3775);
DISPLAY INVISIBLE (-475 3775);
FORCEPROP 1 LAST BODY_TYPE PLUMBING
J 0
(-595 3782);
DISPLAY 0.340426 (-595 3782);
PAINT GREEN (-595 3782);
DISPLAY INVISIBLE (-595 3782);
FORCEPROP 1 LAST HDL_POWER GND
J 0
(-550 3975);
DISPLAY 1.723404 (-550 3975);
PAINT GREEN (-550 3975);
DISPLAY INVISIBLE (-550 3975);
FORCEADD PVCCIN_CPU1..1
(-975 3625);
FORCEPROP 3 LASTPIN (-975 3575) SIG_NAME PVCCIN_CPU1\g
J 0
(-965 3585);
DISPLAY 0.659574 (-965 3585);
PAINT MONO (-965 3585);
DISPLAY INVISIBLE (-965 3585);
FORCEPROP 1 LAST VOLTAGE 2.0V
J 0
(-1020 3582);
DISPLAY 0.340426 (-1020 3582);
PAINT SKYBLUE (-1020 3582);
DISPLAY INVISIBLE (-1020 3582);
FORCEPROP 1 LAST PATH I7
J 0
(-925 3650);
DISPLAY 0.872340 (-925 3650);
PAINT AQUA (-925 3650);
DISPLAY INVISIBLE (-925 3650);
FORCEPROP 2 LAST CDS_LIB mstr_symbols
J 0
(-975 3625);
PAINT ORANGE (-975 3625);
DISPLAY INVISIBLE (-975 3625);
FORCEPROP 1 LAST BODY_TYPE PLUMBING
J 0
(-1020 3582);
DISPLAY 0.340426 (-1020 3582);
PAINT GREEN (-1020 3582);
DISPLAY INVISIBLE (-1020 3582);
FORCEPROP 1 LAST HDL_POWER PVCCIN_CPU1
J 1
(-975 3675);
DISPLAY 0.872340 (-975 3675);
PAINT GREEN (-975 3675);
DISPLAY INVISIBLE (-975 3675);
FORCEADD GND..1
(-1025 1175);
FORCEPROP 3 LASTPIN (-1025 1225) SIG_NAME GND\g
J 0
(-1015 1235);
DISPLAY 0.659574 (-1015 1235);
PAINT MONO (-1015 1235);
DISPLAY INVISIBLE (-1015 1235);
FORCEPROP 2 LAST ROOM PVCCIN_CPU1_PWR_VR
J 0
(-1575 1250);
DISPLAY 1.936170 (-1575 1250);
PAINT ORANGE (-1575 1250);
DISPLAY INVISIBLE (-1575 1250);
FORCEPROP 2 LAST BOM_COST PROC_VRD_VCCIN_CPU0
J 0
(-1400 1250);
DISPLAY 1.446809 (-1400 1250);
PAINT MONO (-1400 1250);
DISPLAY INVISIBLE (-1400 1250);
FORCEPROP 2 LAST CDS_LIB mstr_symbols
J 0
(-1025 1175);
PAINT ORANGE (-1025 1175);
DISPLAY INVISIBLE (-1025 1175);
FORCEPROP 1 LAST VOLTAGE 0
J 0
(-1025 1175);
PAINT SKYBLUE (-1025 1175);
DISPLAY INVISIBLE (-1025 1175);
FORCEPROP 1 LAST PATH I70
J 0
(-950 1175);
DISPLAY 0.872340 (-950 1175);
PAINT AQUA (-950 1175);
DISPLAY INVISIBLE (-950 1175);
FORCEPROP 1 LAST SIZE 1B
J 0
(-950 1125);
DISPLAY 1.723404 (-950 1125);
PAINT GREEN (-950 1125);
DISPLAY INVISIBLE (-950 1125);
FORCEPROP 1 LAST BODY_TYPE PLUMBING
J 0
(-1070 1132);
DISPLAY 0.340426 (-1070 1132);
PAINT GREEN (-1070 1132);
DISPLAY INVISIBLE (-1070 1132);
FORCEPROP 1 LAST HDL_POWER GND
J 0
(-1025 1325);
DISPLAY 1.723404 (-1025 1325);
PAINT GREEN (-1025 1325);
DISPLAY INVISIBLE (-1025 1325);
FORCEADD CAP_A..1
(-4175 3325);
FORCEPROP 1 LAST LOCATION CT24
J 0
(-4300 3250);
DISPLAY 0.617021 (-4300 3250);
PAINT AQUA (-4300 3250);
FORCEPROP 1 LAST VALUE 0.1UF
J 0
(-4125 3375);
DISPLAY 0.617021 (-4125 3375);
PAINT SKYBLUE (-4125 3375);
FORCEPROP 1 LAST VOLTAGE 16V
J 0
(-4125 3325);
DISPLAY 0.617021 (-4125 3325);
PAINT SKYBLUE (-4125 3325);
FORCEPROP 1 LAST TOLERANCE 10%
J 0
(-4125 3275);
DISPLAY 0.617021 (-4125 3275);
PAINT SKYBLUE (-4125 3275);
FORCEPROP 1 LAST MATERIAL X7R
J 0
(-4125 3225);
DISPLAY 0.617021 (-4125 3225);
PAINT SKYBLUE (-4125 3225);
FORCEPROP 1 LAST PACK_TYPE 0402V
J 0
(-4125 3125);
DISPLAY 0.617021 (-4125 3125);
PAINT SKYBLUE (-4125 3125);
FORCEPROP 1 LAST PART_NUMBER A36096-030
J 0
(-4125 3175);
DISPLAY 0.617021 (-4125 3175);
PAINT BLUE (-4125 3175);
FORCEPROP 0 LAST STATUS NOPOP
J 0
(-4400 3175);
DISPLAY 1.021277 (-4400 3175);
PAINT ORANGE (-4400 3175);
FORCEPROP 1 LASTPIN (-4175 3225) $PN 2
J 0
(-4165 3205);
DISPLAY 0.787234 (-4165 3205);
PAINT ORANGE (-4165 3205);
DISPLAY INVISIBLE (-4165 3205);
FORCEPROP 1 LASTPIN (-4175 3425) $PN 1
J 0
(-4165 3405);
DISPLAY 0.787234 (-4165 3405);
PAINT ORANGE (-4165 3405);
DISPLAY INVISIBLE (-4165 3405);
FORCEPROP 2 LAST ROOM PVCCIN_CPU0_PWR_VR
J 0
(-4125 3475);
DISPLAY 1.361702 (-4125 3475);
PAINT ORANGE (-4125 3475);
DISPLAY INVISIBLE (-4125 3475);
FORCEPROP 1 LAST PATH I71
J 0
(-4125 3475);
DISPLAY 0.978723 (-4125 3475);
PAINT WHITE (-4125 3475);
DISPLAY INVISIBLE (-4125 3475);
FORCEPROP 2 LAST CDS_LIB dev_discrete
J 0
(-4175 3325);
PAINT MONO (-4175 3325);
DISPLAY INVISIBLE (-4175 3325);
FORCEADD GND..1
(-4175 3000);
FORCEPROP 3 LASTPIN (-4175 3050) SIG_NAME GND\g
J 0
(-4165 3060);
DISPLAY 0.659574 (-4165 3060);
PAINT MONO (-4165 3060);
DISPLAY INVISIBLE (-4165 3060);
FORCEPROP 2 LAST ROOM PVCCIN_CPU0_PWR_VR
J 0
(-4725 3075);
DISPLAY 1.936170 (-4725 3075);
PAINT ORANGE (-4725 3075);
DISPLAY INVISIBLE (-4725 3075);
FORCEPROP 2 LAST BOM_COST PROC_VRD_VCCIN_CPU0
J 0
(-4550 3075);
DISPLAY 1.446809 (-4550 3075);
PAINT MONO (-4550 3075);
DISPLAY INVISIBLE (-4550 3075);
FORCEPROP 1 LAST SIZE 1B
J 0
(-4100 2950);
DISPLAY 1.723404 (-4100 2950);
PAINT GREEN (-4100 2950);
DISPLAY INVISIBLE (-4100 2950);
FORCEPROP 1 LAST VOLTAGE 0
J 0
(-4175 3000);
PAINT SKYBLUE (-4175 3000);
DISPLAY INVISIBLE (-4175 3000);
FORCEPROP 1 LAST PATH I72
J 0
(-4100 3000);
DISPLAY 0.872340 (-4100 3000);
PAINT AQUA (-4100 3000);
DISPLAY INVISIBLE (-4100 3000);
FORCEPROP 2 LAST CDS_LIB mstr_symbols
J 0
(-4175 3000);
PAINT MONO (-4175 3000);
DISPLAY INVISIBLE (-4175 3000);
FORCEPROP 1 LAST BODY_TYPE PLUMBING
J 0
(-4220 2957);
DISPLAY 0.340426 (-4220 2957);
PAINT GREEN (-4220 2957);
DISPLAY INVISIBLE (-4220 2957);
FORCEPROP 1 LAST HDL_POWER GND
J 0
(-4175 3150);
DISPLAY 1.723404 (-4175 3150);
PAINT GREEN (-4175 3150);
DISPLAY INVISIBLE (-4175 3150);
FORCEADD CAP..1
(-2450 3825);
FORCEPROP 1 LAST TOLERANCE 10%
J 0
(-2400 3775);
DISPLAY 0.617021 (-2400 3775);
PAINT SKYBLUE (-2400 3775);
FORCEPROP 1 LAST VALUE 1000PF
J 0
(-2400 3875);
DISPLAY 0.617021 (-2400 3875);
PAINT SKYBLUE (-2400 3875);
FORCEPROP 1 LAST MATERIAL X7R
J 0
(-2400 3725);
DISPLAY 0.617021 (-2400 3725);
PAINT SKYBLUE (-2400 3725);
FORCEPROP 1 LAST PACK_TYPE 0402LF
J 0
(-2400 3625);
DISPLAY 0.617021 (-2400 3625);
PAINT SKYBLUE (-2400 3625);
FORCEPROP 1 LAST PART_NUMBER A36096-046
J 0
(-2400 3675);
DISPLAY 0.617021 (-2400 3675);
PAINT BLUE (-2400 3675);
FORCEPROP 1 LAST VOLTAGE 50V
J 0
(-2400 3825);
DISPLAY 0.617021 (-2400 3825);
PAINT SKYBLUE (-2400 3825);
FORCEPROP 1 LAST LOCATION CT22
J 0
(-2600 3825);
DISPLAY 0.617021 (-2600 3825);
PAINT AQUA (-2600 3825);
FORCEPROP 0 LAST STATUS NOPOP
J 0
(-2400 3925);
DISPLAY 1.021277 (-2400 3925);
PAINT ORANGE (-2400 3925);
FORCEPROP 1 LASTPIN (-2450 3925) $PN 1
J 0
(-2440 3905);
DISPLAY 0.787234 (-2440 3905);
PAINT ORANGE (-2440 3905);
DISPLAY INVISIBLE (-2440 3905);
FORCEPROP 1 LASTPIN (-2450 3725) $PN 2
J 0
(-2440 3705);
DISPLAY 0.787234 (-2440 3705);
PAINT ORANGE (-2440 3705);
DISPLAY INVISIBLE (-2440 3705);
FORCEPROP 0 LAST ROOM VDDQ_KLM_PWR_VR
J 0
(-2400 4025);
DISPLAY 1.021277 (-2400 4025);
PAINT ORANGE (-2400 4025);
DISPLAY INVISIBLE (-2400 4025);
FORCEPROP 1 LAST PATH I74
J 0
(-2400 3975);
DISPLAY 0.978723 (-2400 3975);
PAINT WHITE (-2400 3975);
DISPLAY INVISIBLE (-2400 3975);
FORCEPROP 2 LAST CDS_LIB mstr_discrete
J 0
(-2450 3825);
PAINT MONO (-2450 3825);
DISPLAY INVISIBLE (-2450 3825);
FORCEADD GND..1
(-2450 3625);
FORCEPROP 3 LASTPIN (-2450 3675) SIG_NAME GND\g
J 0
(-2440 3685);
DISPLAY 0.659574 (-2440 3685);
PAINT MONO (-2440 3685);
DISPLAY INVISIBLE (-2440 3685);
FORCEPROP 2 LAST ROOM VDDQ_KLM_PWR_VR
J 0
(-3025 3700);
DISPLAY 1.361702 (-3025 3700);
PAINT ORANGE (-3025 3700);
DISPLAY INVISIBLE (-3025 3700);
FORCEPROP 1 LAST VOLTAGE 0
J 0
(-2450 3625);
PAINT SKYBLUE (-2450 3625);
DISPLAY INVISIBLE (-2450 3625);
FORCEPROP 1 LAST SIZE 1B
J 0
(-2375 3575);
DISPLAY 1.170213 (-2375 3575);
PAINT AQUA (-2375 3575);
DISPLAY INVISIBLE (-2375 3575);
FORCEPROP 1 LAST PATH I75
J 0
(-2375 3625);
DISPLAY 0.872340 (-2375 3625);
PAINT AQUA (-2375 3625);
DISPLAY INVISIBLE (-2375 3625);
FORCEPROP 2 LAST CDS_LIB mstr_symbols
J 0
(-2450 3625);
PAINT MONO (-2450 3625);
DISPLAY INVISIBLE (-2450 3625);
FORCEPROP 1 LAST BODY_TYPE PLUMBING
J 0
(-2495 3582);
DISPLAY 0.340426 (-2495 3582);
PAINT GREEN (-2495 3582);
DISPLAY INVISIBLE (-2495 3582);
FORCEPROP 1 LAST HDL_POWER GND
J 0
(-2450 3775);
DISPLAY 1.170213 (-2450 3775);
PAINT GREEN (-2450 3775);
DISPLAY INVISIBLE (-2450 3775);
FORCEADD 3D01R5F-GP..1
R 4
(-2400 3075);
FORCEPROP 1 LAST VALUE 3D01R5F-GP
J 0
(-2650 3025);
DISPLAY 0.617021 (-2650 3025);
PAINT GREEN (-2650 3025);
FORCEPROP 1 LAST LOCATION RT16
J 0
(-2525 3070);
DISPLAY 0.617021 (-2525 3070);
PAINT GREEN (-2525 3070);
FORCEPROP 0 LAST STATUS NOPOP
J 0
(-2650 3125);
DISPLAY 1.021277 (-2650 3125);
PAINT ORANGE (-2650 3125);
FORCEPROP 1 LAST CDS_LMAN_SYM_OUTLINE -50,75,50,-75
R 2
J 0
(-2400 3075);
DISPLAY 0.468085 (-2400 3075);
PAINT GREEN (-2400 3075);
DISPLAY INVISIBLE (-2400 3075);
FORCEPROP 1 LAST PATH I76
R 2
J 0
(-2400 3075);
DISPLAY 0.617021 (-2400 3075);
PAINT GREEN (-2400 3075);
DISPLAY INVISIBLE (-2400 3075);
FORCEPROP 2 LAST CDS_LIB w_hdl
J 0
(-2400 3075);
PAINT MONO (-2400 3075);
DISPLAY INVISIBLE (-2400 3075);
FORCEPROP 1 LAST PART_NUMBER 64.3R015.16L
R 2
J 0
(-2400 3075);
DISPLAY 0.617021 (-2400 3075);
PAINT GREEN (-2400 3075);
DISPLAY INVISIBLE (-2400 3075);
FORCEPROP 1 LAST PACK_TYPE SMD-RG5
R 2
J 0
(-2400 3075);
DISPLAY 0.617021 (-2400 3075);
PAINT GREEN (-2400 3075);
DISPLAY INVISIBLE (-2400 3075);
FORCEPROP 2 LASTPIN (-2400 3200) SIG_NAME UN$207$3D01R5F-GP$I76$2
J 0
(-2390 3210);
DISPLAY 0.659574 (-2390 3210);
PAINT MONO (-2390 3210);
DISPLAY INVISIBLE (-2390 3210);
FORCEADD SC2K2P50V3KX-GP..1
(-2400 3375);
FORCEPROP 0 LAST STATUS NOPOP
J 0
(-2650 3400);
DISPLAY 1.021277 (-2650 3400);
PAINT ORANGE (-2650 3400);
FORCEPROP 1 LAST VALUE SC2K2P50V3KX-GP
J 0
(-2375 3325);
DISPLAY 0.617021 (-2375 3325);
PAINT GREEN (-2375 3325);
FORCEPROP 1 LAST LOCATION CT23
J 0
(-2375 3405);
DISPLAY 0.617021 (-2375 3405);
PAINT GREEN (-2375 3405);
FORCEPROP 1 LAST PACK_TYPE SMD-BCG6
J 0
(-2400 3375);
DISPLAY 0.617021 (-2400 3375);
PAINT GREEN (-2400 3375);
DISPLAY INVISIBLE (-2400 3375);
FORCEPROP 1 LAST PART_NUMBER 78.22224.2BL
J 0
(-2400 3375);
DISPLAY 0.617021 (-2400 3375);
PAINT GREEN (-2400 3375);
DISPLAY INVISIBLE (-2400 3375);
FORCEPROP 1 LAST PATH I77
J 0
(-2400 3375);
DISPLAY 0.617021 (-2400 3375);
PAINT GREEN (-2400 3375);
DISPLAY INVISIBLE (-2400 3375);
FORCEPROP 2 LAST CDS_LIB w_hdl
J 0
(-2400 3375);
PAINT MONO (-2400 3375);
DISPLAY INVISIBLE (-2400 3375);
FORCEPROP 1 LAST CDS_LMAN_SYM_OUTLINE -50,25,50,-25
J 0
(-2400 3375);
DISPLAY 0.468085 (-2400 3375);
PAINT GREEN (-2400 3375);
DISPLAY INVISIBLE (-2400 3375);
FORCEADD GND..1
(-2400 2850);
FORCEPROP 3 LASTPIN (-2400 2900) SIG_NAME GND\g
J 0
(-2390 2910);
DISPLAY 0.659574 (-2390 2910);
PAINT MONO (-2390 2910);
DISPLAY INVISIBLE (-2390 2910);
FORCEPROP 2 LAST CDS_LIB mstr_symbols
J 0
(-2400 2850);
PAINT MONO (-2400 2850);
DISPLAY INVISIBLE (-2400 2850);
FORCEPROP 1 LAST PATH I78
J 0
(-2325 2850);
DISPLAY 0.872340 (-2325 2850);
PAINT AQUA (-2325 2850);
DISPLAY INVISIBLE (-2325 2850);
FORCEPROP 1 LAST SIZE 1B
J 0
(-2325 2800);
DISPLAY 1.723404 (-2325 2800);
PAINT GREEN (-2325 2800);
DISPLAY INVISIBLE (-2325 2800);
FORCEPROP 1 LAST VOLTAGE 0
J 0
(-2400 2850);
PAINT SKYBLUE (-2400 2850);
DISPLAY INVISIBLE (-2400 2850);
FORCEPROP 2 LAST BOM_COST PROC_VRD_VCCIN_CPU0
J 0
(-2775 2925);
DISPLAY 1.446809 (-2775 2925);
PAINT MONO (-2775 2925);
DISPLAY INVISIBLE (-2775 2925);
FORCEPROP 2 LAST ROOM PVCCIN_CPU0_PWR_VR
J 0
(-2950 2925);
DISPLAY 1.936170 (-2950 2925);
PAINT ORANGE (-2950 2925);
DISPLAY INVISIBLE (-2950 2925);
FORCEPROP 1 LAST BODY_TYPE PLUMBING
J 0
(-2445 2807);
DISPLAY 0.340426 (-2445 2807);
PAINT GREEN (-2445 2807);
DISPLAY INVISIBLE (-2445 2807);
FORCEPROP 1 LAST HDL_POWER GND
J 0
(-2400 3000);
DISPLAY 1.723404 (-2400 3000);
PAINT GREEN (-2400 3000);
DISPLAY INVISIBLE (-2400 3000);
FORCEADD CAP_A..1
(-1425 3325);
FORCEPROP 1 LASTPIN (-1425 3225) $PN 2
J 0
(-1415 3205);
DISPLAY 0.617021 (-1415 3205);
PAINT GREEN (-1415 3205);
FORCEPROP 1 LAST MATERIAL X6S
J 0
(-1375 3225);
DISPLAY 0.617021 (-1375 3225);
PAINT SKYBLUE (-1375 3225);
FORCEPROP 1 LAST TOLERANCE 20%
J 0
(-1375 3275);
DISPLAY 0.617021 (-1375 3275);
PAINT SKYBLUE (-1375 3275);
FORCEPROP 1 LAST VOLTAGE 4V
J 0
(-1375 3325);
DISPLAY 0.617021 (-1375 3325);
PAINT SKYBLUE (-1375 3325);
FORCEPROP 1 LASTPIN (-1425 3425) $PN 1
J 0
(-1415 3405);
DISPLAY 0.617021 (-1415 3405);
PAINT GREEN (-1415 3405);
FORCEPROP 1 LAST VALUE 22.0UF
J 0
(-1375 3375);
DISPLAY 0.617021 (-1375 3375);
PAINT SKYBLUE (-1375 3375);
FORCEPROP 1 LAST PART_NUMBER E15431-004
J 0
(-1375 3175);
DISPLAY 0.617021 (-1375 3175);
PAINT BLUE (-1375 3175);
FORCEPROP 1 LAST LOCATION C9R8
J 0
(-1375 3425);
DISPLAY 0.617021 (-1375 3425);
PAINT AQUA (-1375 3425);
FORCEPROP 1 LAST PACK_TYPE 0603V
J 0
(-1375 3125);
DISPLAY 0.617021 (-1375 3125);
PAINT SKYBLUE (-1375 3125);
FORCEPROP 2 LAST CDS_LIB dev_discrete
J 0
(-1425 3325);
PAINT ORANGE (-1425 3325);
DISPLAY INVISIBLE (-1425 3325);
FORCEPROP 2 LAST CDS_LOCATION C9R8
J 0
(-1375 3425);
DISPLAY 0.617021 (-1375 3425);
PAINT AQUA (-1375 3425);
DISPLAY INVISIBLE (-1375 3425);
FORCEPROP 2 LAST BOM_COST PROC_VRD_VCCIN_CPU0
J 0
(-1375 3475);
DISPLAY 1.446809 (-1375 3475);
PAINT MONO (-1375 3475);
DISPLAY INVISIBLE (-1375 3475);
FORCEPROP 2 LAST CDS_SEC 1
J 0
(-1375 3475);
PAINT ORANGE (-1375 3475);
DISPLAY INVISIBLE (-1375 3475);
FORCEPROP 2 LAST SEC_TYPE 0603V
J 0
(-1370 3525);
DISPLAY 1.021277 (-1370 3525);
PAINT ORANGE (-1370 3525);
DISPLAY INVISIBLE (-1370 3525);
FORCEPROP 2 LAST SEC 1
J 0
(-1370 3525);
DISPLAY 0.680851 (-1370 3525);
PAINT MONO (-1370 3525);
DISPLAY INVISIBLE (-1370 3525);
FORCEPROP 1 LAST PATH I8
J 0
(-1375 3475);
DISPLAY 0.978723 (-1375 3475);
PAINT WHITE (-1375 3475);
DISPLAY INVISIBLE (-1375 3475);
FORCEPROP 2 LAST ROOM PVCCIN_CPU1_PWR_VR
J 0
(-1375 3475);
DISPLAY 1.446809 (-1375 3475);
PAINT MONO (-1375 3475);
DISPLAY INVISIBLE (-1375 3475);
FORCEADD GND..1
(-4150 475);
FORCEPROP 3 LASTPIN (-4150 525) SIG_NAME GND\g
J 0
(-4140 535);
DISPLAY 0.659574 (-4140 535);
PAINT MONO (-4140 535);
DISPLAY INVISIBLE (-4140 535);
FORCEPROP 2 LAST ROOM PVCCIN_CPU0_PWR_VR
J 0
(-4700 550);
DISPLAY 1.936170 (-4700 550);
PAINT ORANGE (-4700 550);
DISPLAY INVISIBLE (-4700 550);
FORCEPROP 2 LAST BOM_COST PROC_VRD_VCCIN_CPU0
J 0
(-4525 550);
DISPLAY 1.446809 (-4525 550);
PAINT MONO (-4525 550);
DISPLAY INVISIBLE (-4525 550);
FORCEPROP 1 LAST SIZE 1B
J 0
(-4075 425);
DISPLAY 1.723404 (-4075 425);
PAINT GREEN (-4075 425);
DISPLAY INVISIBLE (-4075 425);
FORCEPROP 1 LAST VOLTAGE 0
J 0
(-4150 475);
PAINT SKYBLUE (-4150 475);
DISPLAY INVISIBLE (-4150 475);
FORCEPROP 1 LAST PATH I80
J 0
(-4075 475);
DISPLAY 0.872340 (-4075 475);
PAINT AQUA (-4075 475);
DISPLAY INVISIBLE (-4075 475);
FORCEPROP 2 LAST CDS_LIB mstr_symbols
J 0
(-4150 475);
PAINT MONO (-4150 475);
DISPLAY INVISIBLE (-4150 475);
FORCEPROP 1 LAST BODY_TYPE PLUMBING
J 0
(-4195 432);
DISPLAY 0.340426 (-4195 432);
PAINT GREEN (-4195 432);
DISPLAY INVISIBLE (-4195 432);
FORCEPROP 1 LAST HDL_POWER GND
J 0
(-4150 625);
DISPLAY 1.723404 (-4150 625);
PAINT GREEN (-4150 625);
DISPLAY INVISIBLE (-4150 625);
FORCEADD CAP_A..1
(-4150 725);
FORCEPROP 0 LAST STATUS NOPOP
J 0
(-4375 625);
DISPLAY 1.021277 (-4375 625);
PAINT ORANGE (-4375 625);
FORCEPROP 1 LAST LOCATION CT25
J 0
(-4300 700);
DISPLAY 0.617021 (-4300 700);
PAINT AQUA (-4300 700);
FORCEPROP 1 LAST PACK_TYPE 0402V
J 0
(-4100 525);
DISPLAY 0.617021 (-4100 525);
PAINT SKYBLUE (-4100 525);
FORCEPROP 1 LAST PART_NUMBER A36096-030
J 0
(-4100 575);
DISPLAY 0.617021 (-4100 575);
PAINT BLUE (-4100 575);
FORCEPROP 1 LAST MATERIAL X7R
J 0
(-4100 625);
DISPLAY 0.617021 (-4100 625);
PAINT SKYBLUE (-4100 625);
FORCEPROP 1 LAST TOLERANCE 10%
J 0
(-4100 675);
DISPLAY 0.617021 (-4100 675);
PAINT SKYBLUE (-4100 675);
FORCEPROP 1 LAST VOLTAGE 16V
J 0
(-4100 725);
DISPLAY 0.617021 (-4100 725);
PAINT SKYBLUE (-4100 725);
FORCEPROP 1 LAST VALUE 0.1UF
J 0
(-4100 775);
DISPLAY 0.617021 (-4100 775);
PAINT SKYBLUE (-4100 775);
FORCEPROP 1 LASTPIN (-4150 625) $PN 2
J 0
(-4140 605);
DISPLAY 0.787234 (-4140 605);
PAINT ORANGE (-4140 605);
DISPLAY INVISIBLE (-4140 605);
FORCEPROP 1 LASTPIN (-4150 825) $PN 1
J 0
(-4140 805);
DISPLAY 0.787234 (-4140 805);
PAINT ORANGE (-4140 805);
DISPLAY INVISIBLE (-4140 805);
FORCEPROP 2 LAST ROOM PVCCIN_CPU0_PWR_VR
J 0
(-4100 875);
DISPLAY 1.361702 (-4100 875);
PAINT ORANGE (-4100 875);
DISPLAY INVISIBLE (-4100 875);
FORCEPROP 1 LAST PATH I81
J 0
(-4100 875);
DISPLAY 0.978723 (-4100 875);
PAINT WHITE (-4100 875);
DISPLAY INVISIBLE (-4100 875);
FORCEPROP 2 LAST CDS_LIB dev_discrete
J 0
(-4150 725);
PAINT MONO (-4150 725);
DISPLAY INVISIBLE (-4150 725);
FORCEADD CAP..1
(-2400 1225);
FORCEPROP 1 LAST PART_NUMBER A36096-046
J 0
(-2350 1075);
DISPLAY 0.617021 (-2350 1075);
PAINT BLUE (-2350 1075);
FORCEPROP 1 LAST LOCATION CT26
J 0
(-2550 1225);
DISPLAY 0.617021 (-2550 1225);
PAINT AQUA (-2550 1225);
FORCEPROP 1 LAST TOLERANCE 10%
J 0
(-2350 1175);
DISPLAY 0.617021 (-2350 1175);
PAINT SKYBLUE (-2350 1175);
FORCEPROP 0 LAST STATUS NOPOP
J 0
(-2375 1325);
DISPLAY 1.021277 (-2375 1325);
PAINT ORANGE (-2375 1325);
FORCEPROP 1 LAST MATERIAL X7R
J 0
(-2350 1125);
DISPLAY 0.617021 (-2350 1125);
PAINT SKYBLUE (-2350 1125);
FORCEPROP 1 LAST VALUE 1000PF
J 0
(-2350 1275);
DISPLAY 0.617021 (-2350 1275);
PAINT SKYBLUE (-2350 1275);
FORCEPROP 1 LAST VOLTAGE 50V
J 0
(-2350 1225);
DISPLAY 0.617021 (-2350 1225);
PAINT SKYBLUE (-2350 1225);
FORCEPROP 1 LAST PACK_TYPE 0402LF
J 0
(-2350 1025);
DISPLAY 0.617021 (-2350 1025);
PAINT SKYBLUE (-2350 1025);
FORCEPROP 1 LASTPIN (-2400 1325) $PN 1
J 0
(-2390 1305);
DISPLAY 0.787234 (-2390 1305);
PAINT ORANGE (-2390 1305);
DISPLAY INVISIBLE (-2390 1305);
FORCEPROP 1 LASTPIN (-2400 1125) $PN 2
J 0
(-2390 1105);
DISPLAY 0.787234 (-2390 1105);
PAINT ORANGE (-2390 1105);
DISPLAY INVISIBLE (-2390 1105);
FORCEPROP 0 LAST ROOM VDDQ_KLM_PWR_VR
J 0
(-2350 1425);
DISPLAY 1.021277 (-2350 1425);
PAINT ORANGE (-2350 1425);
DISPLAY INVISIBLE (-2350 1425);
FORCEPROP 1 LAST PATH I82
J 0
(-2350 1375);
DISPLAY 0.978723 (-2350 1375);
PAINT WHITE (-2350 1375);
DISPLAY INVISIBLE (-2350 1375);
FORCEPROP 2 LAST CDS_LIB mstr_discrete
J 0
(-2400 1225);
PAINT MONO (-2400 1225);
DISPLAY INVISIBLE (-2400 1225);
FORCEADD GND..1
(-2400 1025);
FORCEPROP 3 LASTPIN (-2400 1075) SIG_NAME GND\g
J 0
(-2390 1085);
DISPLAY 0.659574 (-2390 1085);
PAINT MONO (-2390 1085);
DISPLAY INVISIBLE (-2390 1085);
FORCEPROP 1 LAST SIZE 1B
J 0
(-2325 975);
DISPLAY 1.170213 (-2325 975);
PAINT AQUA (-2325 975);
DISPLAY INVISIBLE (-2325 975);
FORCEPROP 1 LAST VOLTAGE 0
J 0
(-2400 1025);
PAINT SKYBLUE (-2400 1025);
DISPLAY INVISIBLE (-2400 1025);
FORCEPROP 2 LAST ROOM VDDQ_KLM_PWR_VR
J 0
(-2975 1100);
DISPLAY 1.361702 (-2975 1100);
PAINT ORANGE (-2975 1100);
DISPLAY INVISIBLE (-2975 1100);
FORCEPROP 1 LAST PATH I83
J 0
(-2325 1025);
DISPLAY 0.872340 (-2325 1025);
PAINT AQUA (-2325 1025);
DISPLAY INVISIBLE (-2325 1025);
FORCEPROP 2 LAST CDS_LIB mstr_symbols
J 0
(-2400 1025);
PAINT MONO (-2400 1025);
DISPLAY INVISIBLE (-2400 1025);
FORCEPROP 1 LAST BODY_TYPE PLUMBING
J 0
(-2445 982);
DISPLAY 0.340426 (-2445 982);
PAINT GREEN (-2445 982);
DISPLAY INVISIBLE (-2445 982);
FORCEPROP 1 LAST HDL_POWER GND
J 0
(-2400 1175);
DISPLAY 1.170213 (-2400 1175);
PAINT GREEN (-2400 1175);
DISPLAY INVISIBLE (-2400 1175);
FORCEADD SC2K2P50V3KX-GP..1
(-2350 825);
FORCEPROP 1 LAST VALUE SC2K2P50V3KX-GP
J 0
(-2325 775);
DISPLAY 0.617021 (-2325 775);
PAINT GREEN (-2325 775);
FORCEPROP 1 LAST LOCATION CT27
J 0
(-2325 855);
DISPLAY 0.617021 (-2325 855);
PAINT GREEN (-2325 855);
FORCEPROP 0 LAST STATUS NOPOP
J 0
(-2575 750);
DISPLAY 1.021277 (-2575 750);
PAINT ORANGE (-2575 750);
FORCEPROP 1 LAST PACK_TYPE SMD-BCG6
J 0
(-2350 825);
DISPLAY 0.617021 (-2350 825);
PAINT GREEN (-2350 825);
DISPLAY INVISIBLE (-2350 825);
FORCEPROP 1 LAST PART_NUMBER 78.22224.2BL
J 0
(-2350 825);
DISPLAY 0.617021 (-2350 825);
PAINT GREEN (-2350 825);
DISPLAY INVISIBLE (-2350 825);
FORCEPROP 1 LAST PATH I84
J 0
(-2350 825);
DISPLAY 0.617021 (-2350 825);
PAINT GREEN (-2350 825);
DISPLAY INVISIBLE (-2350 825);
FORCEPROP 2 LAST CDS_LIB w_hdl
J 0
(-2350 825);
PAINT MONO (-2350 825);
DISPLAY INVISIBLE (-2350 825);
FORCEPROP 1 LAST CDS_LMAN_SYM_OUTLINE -50,25,50,-25
J 0
(-2350 825);
DISPLAY 0.468085 (-2350 825);
PAINT GREEN (-2350 825);
DISPLAY INVISIBLE (-2350 825);
FORCEADD 3D01R5F-GP..1
R 4
(-2350 550);
FORCEPROP 1 LAST VALUE 3D01R5F-GP
J 0
(-2575 450);
DISPLAY 0.617021 (-2575 450);
PAINT GREEN (-2575 450);
FORCEPROP 0 LAST STATUS NOPOP
J 0
(-2575 500);
DISPLAY 1.021277 (-2575 500);
PAINT ORANGE (-2575 500);
FORCEPROP 1 LAST LOCATION RT18
J 0
(-2475 545);
DISPLAY 0.617021 (-2475 545);
PAINT GREEN (-2475 545);
FORCEPROP 1 LAST CDS_LMAN_SYM_OUTLINE -50,75,50,-75
R 2
J 0
(-2350 550);
DISPLAY 0.468085 (-2350 550);
PAINT GREEN (-2350 550);
DISPLAY INVISIBLE (-2350 550);
FORCEPROP 1 LAST PATH I85
R 2
J 0
(-2350 550);
DISPLAY 0.617021 (-2350 550);
PAINT GREEN (-2350 550);
DISPLAY INVISIBLE (-2350 550);
FORCEPROP 2 LAST CDS_LIB w_hdl
J 0
(-2350 550);
PAINT MONO (-2350 550);
DISPLAY INVISIBLE (-2350 550);
FORCEPROP 1 LAST PART_NUMBER 64.3R015.16L
R 2
J 0
(-2350 550);
DISPLAY 0.617021 (-2350 550);
PAINT GREEN (-2350 550);
DISPLAY INVISIBLE (-2350 550);
FORCEPROP 1 LAST PACK_TYPE SMD-RG5
R 2
J 0
(-2350 550);
DISPLAY 0.617021 (-2350 550);
PAINT GREEN (-2350 550);
DISPLAY INVISIBLE (-2350 550);
FORCEPROP 2 LASTPIN (-2350 675) SIG_NAME UN$207$3D01R5F-GP$I85$2
J 0
(-2340 685);
DISPLAY 0.659574 (-2340 685);
PAINT MONO (-2340 685);
DISPLAY INVISIBLE (-2340 685);
FORCEADD GND..1
(-2350 375);
FORCEPROP 3 LASTPIN (-2350 425) SIG_NAME GND\g
J 0
(-2340 435);
DISPLAY 0.659574 (-2340 435);
PAINT MONO (-2340 435);
DISPLAY INVISIBLE (-2340 435);
FORCEPROP 2 LAST ROOM PVCCIN_CPU0_PWR_VR
J 0
(-2900 450);
DISPLAY 1.936170 (-2900 450);
PAINT ORANGE (-2900 450);
DISPLAY INVISIBLE (-2900 450);
FORCEPROP 2 LAST BOM_COST PROC_VRD_VCCIN_CPU0
J 0
(-2725 450);
DISPLAY 1.446809 (-2725 450);
PAINT MONO (-2725 450);
DISPLAY INVISIBLE (-2725 450);
FORCEPROP 1 LAST VOLTAGE 0
J 0
(-2350 375);
PAINT SKYBLUE (-2350 375);
DISPLAY INVISIBLE (-2350 375);
FORCEPROP 1 LAST SIZE 1B
J 0
(-2275 325);
DISPLAY 1.723404 (-2275 325);
PAINT GREEN (-2275 325);
DISPLAY INVISIBLE (-2275 325);
FORCEPROP 1 LAST PATH I86
J 0
(-2275 375);
DISPLAY 0.872340 (-2275 375);
PAINT AQUA (-2275 375);
DISPLAY INVISIBLE (-2275 375);
FORCEPROP 2 LAST CDS_LIB mstr_symbols
J 0
(-2350 375);
PAINT MONO (-2350 375);
DISPLAY INVISIBLE (-2350 375);
FORCEPROP 1 LAST BODY_TYPE PLUMBING
J 0
(-2395 332);
DISPLAY 0.340426 (-2395 332);
PAINT GREEN (-2395 332);
DISPLAY INVISIBLE (-2395 332);
FORCEPROP 1 LAST HDL_POWER GND
J 0
(-2350 525);
DISPLAY 1.723404 (-2350 525);
PAINT GREEN (-2350 525);
DISPLAY INVISIBLE (-2350 525);
FORCEADD RES..1
(-5150 3650);
FORCEPROP 1 LAST LOCATION RT15
J 0
(-5300 3650);
DISPLAY 0.617021 (-5300 3650);
PAINT AQUA (-5300 3650);
FORCEPROP 1 LAST WATTAGE 1/16W
J 2
(-5175 3500);
DISPLAY 0.617021 (-5175 3500);
PAINT SKYBLUE (-5175 3500);
FORCEPROP 1 LAST VALUE 0.0
J 2
(-5175 3550);
DISPLAY 0.617021 (-5175 3550);
PAINT SKYBLUE (-5175 3550);
FORCEPROP 1 LAST TOLERANCE 5%
J 0
(-5150 3550);
DISPLAY 0.617021 (-5150 3550);
PAINT SKYBLUE (-5150 3550);
FORCEPROP 1 LAST MATERIAL CHIP
J 0
(-5175 3500);
DISPLAY 0.617021 (-5175 3500);
PAINT SKYBLUE (-5175 3500);
FORCEPROP 1 LAST PACK_TYPE 0402
J 0
(-5075 3500);
DISPLAY 0.617021 (-5075 3500);
PAINT SKYBLUE (-5075 3500);
FORCEPROP 1 LAST PART_NUMBER G21497-005
J 0
(-5275 3600);
DISPLAY 0.617021 (-5275 3600);
PAINT BLUE (-5275 3600);
FORCEPROP 2 LAST CDS_LIB mstr_discrete
J 0
(-5150 3650);
PAINT MONO (-5150 3650);
DISPLAY INVISIBLE (-5150 3650);
FORCEPROP 1 LAST PATH I87
J 0
(-5200 3800);
DISPLAY 0.978723 (-5200 3800);
PAINT WHITE (-5200 3800);
DISPLAY INVISIBLE (-5200 3800);
FORCEPROP 2 LAST BOM_COST DEBUG
J 0
(-5200 3850);
DISPLAY 1.021277 (-5200 3850);
PAINT ORANGE (-5200 3850);
DISPLAY INVISIBLE (-5200 3850);
FORCEPROP 2 LAST ROOM BMC_DEBUG_HEADER
J 0
(-5200 3800);
DISPLAY 1.021277 (-5200 3800);
PAINT ORANGE (-5200 3800);
DISPLAY INVISIBLE (-5200 3800);
FORCEPROP 1 LASTPIN (-5250 3650) $PN 1
J 0
(-5238 3662);
DISPLAY 0.787234 (-5238 3662);
PAINT ORANGE (-5238 3662);
DISPLAY INVISIBLE (-5238 3662);
FORCEPROP 1 LASTPIN (-5050 3650) $PN 2
J 0
(-5088 3662);
DISPLAY 0.787234 (-5088 3662);
PAINT ORANGE (-5088 3662);
DISPLAY INVISIBLE (-5088 3662);
FORCEADD RES..1
(-5025 1000);
FORCEPROP 1 LAST PACK_TYPE 0402
J 0
(-4925 850);
DISPLAY 0.617021 (-4925 850);
PAINT SKYBLUE (-4925 850);
FORCEPROP 1 LAST WATTAGE 1/16W
J 2
(-5050 850);
DISPLAY 0.617021 (-5050 850);
PAINT SKYBLUE (-5050 850);
FORCEPROP 1 LAST VALUE 0.0
J 2
(-5050 900);
DISPLAY 0.617021 (-5050 900);
PAINT SKYBLUE (-5050 900);
FORCEPROP 1 LAST PART_NUMBER G21497-005
J 0
(-5125 950);
DISPLAY 0.617021 (-5125 950);
PAINT BLUE (-5125 950);
FORCEPROP 1 LAST TOLERANCE 5%
J 0
(-5025 900);
DISPLAY 0.617021 (-5025 900);
PAINT SKYBLUE (-5025 900);
FORCEPROP 1 LAST MATERIAL CHIP
J 0
(-5025 850);
DISPLAY 0.617021 (-5025 850);
PAINT SKYBLUE (-5025 850);
FORCEPROP 1 LAST LOCATION RT17
J 0
(-5075 1025);
DISPLAY 0.617021 (-5075 1025);
PAINT AQUA (-5075 1025);
FORCEPROP 2 LAST CDS_LIB mstr_discrete
J 0
(-5025 1000);
PAINT MONO (-5025 1000);
DISPLAY INVISIBLE (-5025 1000);
FORCEPROP 1 LAST PATH I88
J 0
(-5075 1150);
DISPLAY 0.978723 (-5075 1150);
PAINT WHITE (-5075 1150);
DISPLAY INVISIBLE (-5075 1150);
FORCEPROP 2 LAST ROOM BMC_DEBUG_HEADER
J 0
(-5075 1150);
DISPLAY 1.021277 (-5075 1150);
PAINT ORANGE (-5075 1150);
DISPLAY INVISIBLE (-5075 1150);
FORCEPROP 2 LAST BOM_COST DEBUG
J 0
(-5075 1200);
DISPLAY 1.021277 (-5075 1200);
PAINT ORANGE (-5075 1200);
DISPLAY INVISIBLE (-5075 1200);
FORCEPROP 1 LASTPIN (-5125 1000) $PN 1
J 0
(-5113 1012);
DISPLAY 0.787234 (-5113 1012);
PAINT ORANGE (-5113 1012);
DISPLAY INVISIBLE (-5113 1012);
FORCEPROP 1 LASTPIN (-4925 1000) $PN 2
J 0
(-4963 1012);
DISPLAY 0.787234 (-4963 1012);
PAINT ORANGE (-4963 1012);
DISPLAY INVISIBLE (-4963 1012);
FORCEADD GND..1
(-1425 3100);
FORCEPROP 3 LASTPIN (-1425 3150) SIG_NAME GND\g
J 0
(-1415 3160);
DISPLAY 0.659574 (-1415 3160);
PAINT MONO (-1415 3160);
DISPLAY INVISIBLE (-1415 3160);
FORCEPROP 1 LAST SIZE 1B
J 0
(-1350 3050);
DISPLAY 1.723404 (-1350 3050);
PAINT GREEN (-1350 3050);
DISPLAY INVISIBLE (-1350 3050);
FORCEPROP 2 LAST ROOM PVCCIN_CPU1_PWR_VR
J 0
(-1975 3175);
DISPLAY 1.936170 (-1975 3175);
PAINT ORANGE (-1975 3175);
DISPLAY INVISIBLE (-1975 3175);
FORCEPROP 2 LAST BOM_COST PROC_VRD_VCCIN_CPU0
J 0
(-1800 3175);
DISPLAY 1.446809 (-1800 3175);
PAINT MONO (-1800 3175);
DISPLAY INVISIBLE (-1800 3175);
FORCEPROP 2 LAST CDS_LIB mstr_symbols
J 0
(-1425 3100);
DISPLAY 1.936170 (-1425 3100);
PAINT ORANGE (-1425 3100);
DISPLAY INVISIBLE (-1425 3100);
FORCEPROP 1 LAST VOLTAGE 0
J 0
(-1425 3100);
PAINT SKYBLUE (-1425 3100);
DISPLAY INVISIBLE (-1425 3100);
FORCEPROP 1 LAST PATH I9
J 0
(-1350 3100);
DISPLAY 0.872340 (-1350 3100);
PAINT AQUA (-1350 3100);
DISPLAY INVISIBLE (-1350 3100);
FORCEPROP 1 LAST BODY_TYPE PLUMBING
J 0
(-1470 3057);
DISPLAY 0.340426 (-1470 3057);
PAINT GREEN (-1470 3057);
DISPLAY INVISIBLE (-1470 3057);
FORCEPROP 1 LAST HDL_POWER GND
J 0
(-1425 3250);
DISPLAY 1.723404 (-1425 3250);
PAINT GREEN (-1425 3250);
DISPLAY INVISIBLE (-1425 3250);
FORCEADD DNS..2
(-545 4020);
PAINT RED (-545 4020);
FORCEPROP 2 LAST CDS_LIB mstr_misc
J 0
(-545 4020);
PAINT ORANGE (-545 4020);
DISPLAY INVISIBLE (-545 4020);
FORCEPROP 1 LAST COMMENT_BODY TRUE
R 1
J 0
(-470 3795);
DISPLAY 0.872340 (-470 3795);
PAINT GREEN (-470 3795);
DISPLAY INVISIBLE (-470 3795);
FORCEADD DNS..2
(-1020 1395);
PAINT RED (-1020 1395);
FORCEPROP 2 LAST CDS_LIB mstr_misc
J 0
(-1020 1395);
PAINT ORANGE (-1020 1395);
DISPLAY INVISIBLE (-1020 1395);
FORCEPROP 1 LAST COMMENT_BODY TRUE
R 1
J 0
(-945 1170);
DISPLAY 0.872340 (-945 1170);
PAINT GREEN (-945 1170);
DISPLAY INVISIBLE (-945 1170);
FORCEADD INTEL_CORP_BPAGE..1
(0 0);
FORCEPROP 1 LAST CDS_CON_LAST_MODIFIED Tue Dec 01 11:52:23 2015
J 0
(-1425 325);
PAINT ORANGE (-1425 325);
DISPLAY INVISIBLE (-1425 325);
FORCEPROP 1 LAST CUSTOM_TXT_CDS <CURRENT_DESIGN_SHEET> OF <TOTAL_DESIGN_SHEETS>
J 0
(-500 25);
PAINT GREEN (-500 25);
FORCEPROP 2 LAST CUSTOM_TXT_CDS <XR_PAGE_TITLE>
J 0
(-7890 5250);
DISPLAY 0.638298 (-7890 5250);
PAINT PINK (-7890 5250);
DISPLAY INVISIBLE (-7890 5250);
FORCEPROP 2 LAST CUSTOM_TXT_CDS <CON_LAST_MODIFIED>
J 0
(-1725 325);
PAINT ORANGE (-1725 325);
FORCEPROP 1 LAST SCH_NUMBER H4694802
J 0
(-1300 150);
DISPLAY 1.212766 (-1300 150);
PAINT YELLOW (-1300 150);
FORCEPROP 1 LAST SCH_DEPT BESD
J 1
(-4450 100);
DISPLAY 1.212766 (-4450 100);
PAINT YELLOW (-4450 100);
FORCEPROP 1 LAST SCH_TITLE VCCIN CPU1 (2 OF 4)
J 0
(-7950 50);
DISPLAY 1.212766 (-7950 50);
PAINT ORANGE (-7950 50);
FORCEPROP 1 LAST SCH_ADDRESS3 Santa Clara, CA 95052-8119
J 0
(-3975 25);
DISPLAY 0.617021 (-3975 25);
PAINT GREEN (-3975 25);
FORCEPROP 1 LAST SCH_ADDRESS2 P.O. BOX 58119
J 0
(-3975 75);
DISPLAY 0.617021 (-3975 75);
PAINT GREEN (-3975 75);
FORCEPROP 1 LAST SCH_ADDRESS1 2200 Mission College Blvd.
J 0
(-3975 125);
DISPLAY 0.617021 (-3975 125);
PAINT GREEN (-3975 125);
FORCEPROP 1 LAST SCH_REV 2.420
J 0
(-250 150);
DISPLAY 0.978723 (-250 150);
PAINT YELLOW (-250 150);
FORCEPROP 2 LAST PAGE_BORDER TRUE
J 0
(-7890 5250);
DISPLAY 0.638298 (-7890 5250);
PAINT PINK (-7890 5250);
DISPLAY INVISIBLE (-7890 5250);
FORCEPROP 2 LAST CDS_LIB mstr_symbols
J 0
(0 0);
PAINT MONO (0 0);
DISPLAY INVISIBLE (0 0);
FORCEPROP 1 LAST COMMENT_BODY TRUE
J 0
(12 12);
DISPLAY 0.468085 (12 12);
PAINT GREEN (12 12);
DISPLAY INVISIBLE (12 12);
FORCEPROP 2 LAST CDS_XR_PAGE_TITLE CR-207 : @BASEBOARD_FAB2_LIB.BASEBOARD_FAB2(SCH_1):PAGE207
J 0
(-7890 5250);
DISPLAY 0.638298 (-7890 5250);
PAINT PINK (-7890 5250);
DISPLAY INVISIBLE (-7890 5250);
WIRE 16 -1 (-3975 1375)(-4075 1375);
WIRE 16 -1 (-4075 1375)(-4075 325);
WIRE 16 -1 (-4075 325)(-1825 325);
WIRE 16 -1 (-1825 925)(-1825 325);
WIRE 16 -1 (-2000 925)(-1825 925);
WIRE 16 -1 (-1825 925)(-1525 925);
WIRE 16 -1 (-1525 875)(-1525 925);
WIRE 16 -1 (-1075 925)(-1525 925);
WIRE 16 -1 (-1075 875)(-1075 925);
WIRE 16 -1 (-1075 925)(-1075 975);
WIRE 16 -1 (-1075 550)(-1525 550);
WIRE 16 -1 (-1075 675)(-1075 550);
WIRE 16 -1 (-1075 500)(-1075 550);
WIRE 16 -1 (-1525 550)(-1525 675);
WIRE 16 -1 (-2725 3375)(-2725 3425);
WIRE 16 -1 (-2950 3375)(-2725 3375);
WIRE 16 -1 (-2725 3325)(-2725 3375);
WIRE 16 -1 (-2725 3425)(-2950 3425);
WIRE 16 -1 (-2950 3325)(-2725 3325);
WIRE 16 -1 (-2725 3275)(-2725 3325);
WIRE 16 -1 (-2725 3125)(-2725 3275);
WIRE 16 -1 (-2725 3275)(-2950 3275);
WIRE 16 -1 (-2975 825)(-2775 825);
WIRE 16 -1 (-2775 775)(-2775 825);
WIRE 16 -1 (-2775 725)(-2775 775);
WIRE 16 -1 (-2775 775)(-2975 775);
WIRE 16 -1 (-2775 675)(-2775 725);
WIRE 16 -1 (-2775 725)(-2975 725);
WIRE 16 -1 (-2775 600)(-2775 675);
WIRE 16 -1 (-2775 675)(-2975 675);
WIRE 16 -1 (-3950 4275)(-4425 4275);
WIRE 16 -1 (-4425 4325)(-4425 4275);
WIRE 16 -1 (-3950 4325)(-4425 4325);
WIRE 16 -1 (-4425 4325)(-6250 4325);
WIRE 16 -1 (-6250 4200)(-6250 4325);
WIRE 16 -1 (-6250 4325)(-6575 4325);
WIRE 16 -1 (-6575 4200)(-6575 4325);
WIRE 16 -1 (-6575 4325)(-6875 4325);
WIRE 16 -1 (-6875 4200)(-6875 4325);
WIRE 16 -1 (-6875 4325)(-7175 4325);
WIRE 16 -1 (-7175 4200)(-7175 4325);
WIRE 16 -1 (-7175 4325)(-7425 4325);
WIRE 16 -1 (-7425 4200)(-7425 4325);
WIRE 16 -1 (-7525 4325)(-7425 4325);
WIRE 16 -1 (-7525 4425)(-7525 4325);
WIRE 16 -1 (-5250 4000)(-5250 3825);
WIRE 16 -1 (-5250 3825)(-5375 3825);
WIRE 16 -1 (-5375 4000)(-5375 3825);
WIRE 16 -1 (-5375 3825)(-5950 3825);
WIRE 16 -1 (-5950 3975)(-5950 3825);
WIRE 16 -1 (-5950 3825)(-6250 3825);
WIRE 16 -1 (-6250 4000)(-6250 3825);
WIRE 16 -1 (-6250 3825)(-6575 3825);
WIRE 16 -1 (-6575 4000)(-6575 3825);
WIRE 16 -1 (-6575 3825)(-6875 3825);
WIRE 16 -1 (-6875 4000)(-6875 3825);
WIRE 16 -1 (-6875 3825)(-7175 3825);
WIRE 16 -1 (-7175 4000)(-7175 3825);
WIRE 16 -1 (-7175 3825)(-7425 3825);
WIRE 16 -1 (-7425 4000)(-7425 3825);
WIRE 16 -1 (-7525 3825)(-7425 3825);
WIRE 16 -1 (-7525 3825)(-7525 3800);
WIRE 16 -1 (-3975 1675)(-4450 1675);
WIRE 16 -1 (-4450 1725)(-4450 1675);
WIRE 16 -1 (-3975 1725)(-4450 1725);
WIRE 16 -1 (-4450 1725)(-6175 1725);
WIRE 16 -1 (-6175 1600)(-6175 1725);
WIRE 16 -1 (-6175 1725)(-6450 1725);
WIRE 16 -1 (-6450 1625)(-6450 1725);
WIRE 16 -1 (-6450 1725)(-6800 1725);
WIRE 16 -1 (-6800 1625)(-6800 1725);
WIRE 16 -1 (-6800 1725)(-7125 1725);
WIRE 16 -1 (-7125 1625)(-7125 1725);
WIRE 16 -1 (-7450 1725)(-7125 1725);
WIRE 16 -1 (-7450 1625)(-7450 1725);
WIRE 16 -1 (-7500 1725)(-7450 1725);
WIRE 16 -1 (-7500 1775)(-7500 1725);
WIRE 16 -1 (-5075 1450)(-5075 1250);
WIRE 16 -1 (-5075 1250)(-5250 1250);
WIRE 16 -1 (-5250 1450)(-5250 1250);
WIRE 16 -1 (-5250 1250)(-5850 1250);
WIRE 16 -1 (-5850 1400)(-5850 1250);
WIRE 16 -1 (-5850 1250)(-6175 1250);
WIRE 16 -1 (-6175 1400)(-6175 1250);
WIRE 16 -1 (-6175 1250)(-6450 1250);
WIRE 16 -1 (-6450 1425)(-6450 1250);
WIRE 16 -1 (-6450 1250)(-6800 1250);
WIRE 16 -1 (-6800 1425)(-6800 1250);
WIRE 16 -1 (-6800 1250)(-7125 1250);
WIRE 16 -1 (-7125 1425)(-7125 1250);
WIRE 16 -1 (-7125 1250)(-7450 1250);
WIRE 16 -1 (-7450 1425)(-7450 1250);
WIRE 16 -1 (-7500 1250)(-7450 1250);
WIRE 16 -1 (-7500 1225)(-7500 1250);
WIRE 16 -1 (-4550 4075)(-3950 4075);
WIRE 16 -1 (-4550 4175)(-4550 4075);
WIRE 16 -1 (-3950 4175)(-4550 4175);
WIRE 16 -1 (-4550 4175)(-4550 4625);
WIRE 16 -1 (-4550 4625)(-5250 4625);
WIRE 16 -1 (-4550 4625)(-4550 4725);
WIRE 16 -1 (-5375 4625)(-5250 4625);
WIRE 16 -1 (-5250 4200)(-5250 4625);
WIRE 16 -1 (-5375 4625)(-5600 4625);
WIRE 16 -1 (-5375 4200)(-5375 4625);
WIRE 16 -1 (-4300 1475)(-3975 1475);
WIRE 16 -1 (-4300 1575)(-4300 1475);
WIRE 16 -1 (-3975 1575)(-4300 1575);
WIRE 16 -1 (-4300 1575)(-4300 2000);
WIRE 16 -1 (-4300 2000)(-5075 2000);
WIRE 16 -1 (-5075 1650)(-5075 2000);
WIRE 16 -1 (-5075 2000)(-5150 2000);
WIRE 16 -1 (-5250 2000)(-5150 2000);
WIRE 16 -1 (-5150 2000)(-5150 2125);
WIRE 16 -1 (-5250 1650)(-5250 2000);
WIRE 16 -1 (-5525 2000)(-5250 2000);
WIRE 16 -1 (-550 3925)(-550 3875);
WIRE 16 -1 (-4100 3975)(-3950 3975);
WIRE 16 -1 (-4100 2775)(-4100 3975);
WIRE 16 -1 (-1650 2775)(-4100 2775);
WIRE 16 -1 (-1650 3525)(-1650 2775);
WIRE 16 -1 (-1900 3525)(-1650 3525);
WIRE 16 -1 (-1650 3525)(-1425 3525);
WIRE 16 -1 (-1425 3425)(-1425 3525);
WIRE 16 -1 (-975 3525)(-1425 3525);
WIRE 16 -1 (-975 3450)(-975 3525);
WIRE 16 -1 (-975 3525)(-975 3575);
WIRE 16 -1 (-1025 1225)(-1025 1300);
WIRE 16 -1 (-4175 3225)(-4175 3050);
WIRE 16 -1 (-2450 3725)(-2450 3675);
WIRE 16 -1 (-2400 2950)(-2400 2900);
WIRE 16 -1 (-4150 625)(-4150 525);
WIRE 16 -1 (-2400 1125)(-2400 1075);
WIRE 16 -1 (-975 3250)(-975 3175);
WIRE 16 -1 (-975 3175)(-1425 3175);
WIRE 16 -1 (-1425 3175)(-1425 3225);
WIRE 16 -1 (-1425 3150)(-1425 3175);
WIRE 3 2175 (-2675 3500)(-2250 3500);
WIRE 3 2175 (-2675 3500)(-2675 2800);
WIRE 3 2175 (-2250 3500)(-2250 2800);
WIRE 3 2175 (-2675 2800)(-2250 2800);
WIRE 16 -1 (-2400 3300)(-2400 3200);
WIRE 3 2175 (-2575 350)(-2175 350);
WIRE 3 2175 (-2575 975)(-2575 350);
WIRE 3 2175 (-2175 975)(-2175 350);
WIRE 3 2175 (-2575 975)(-2175 975);
WIRE 16 -1 (-2350 750)(-2350 675);
WIRE 3 2175 (-4375 975)(-3875 975);
WIRE 3 2175 (-4375 975)(-4375 400);
WIRE 3 2175 (-3875 975)(-3875 400);
WIRE 3 2175 (-4375 400)(-3875 400);
WIRE 16 -1 (-4150 2250)(-1350 2250);
FORCEPROP 2 LAST SIG_NAME VR_PVCCIN_CPU1_AIREF2
J 2
(-3504 2269);
DISPLAY 0.617021 (-3504 2269);
PAINT ORANGE (-3504 2269);
WIRE 16 -1 (-4150 1025)(-4150 2250);
WIRE 16 -1 (-3975 1025)(-4150 1025);
WIRE 16 -1 (-4150 825)(-4150 1025);
WIRE 3 2175 (-2550 1450)(-2150 1450);
WIRE 3 2175 (-2550 1450)(-2550 1000);
WIRE 3 2175 (-2150 1450)(-2150 1000);
WIRE 3 2175 (-2550 1000)(-2150 1000);
WIRE 16 -1 (-2975 1775)(-1325 1775);
FORCEPROP 2 LAST SIG_NAME ISENSE_PVCCIN_CPU1_PH2_IMON
J 0
(-2703 1790);
DISPLAY 0.617021 (-2703 1790);
PAINT ORANGE (-2703 1790);
WIRE 16 -1 (-2975 925)(-2350 925);
FORCEPROP 0 LAST VOLTAGE 5
J 0
(-2700 1000);
DISPLAY 1.021277 (-2700 1000);
PAINT SKYBLUE (-2700 1000);
DISPLAY INVISIBLE (-2700 1000);
FORCEPROP 2 LAST SIG_NAME VR_PVCCIN_CPU1_PHASE2
J 0
(-2865 935);
DISPLAY 0.617021 (-2865 935);
PAINT ORANGE (-2865 935);
FORCEPROP 2 LASTPROP $XRERR UNIQUE?
J 0
(-3105 935);
DISPLAY 0.638298 (-3105 935);
PAINT MONO (-3105 935);
DISPLAY INVISIBLE (-3105 935);
WIRE 16 -1 (-2350 925)(-2200 925);
WIRE 16 -1 (-2350 900)(-2350 925);
WIRE 3 2175 (-2600 4050)(-2175 4050);
WIRE 3 2175 (-2600 4050)(-2600 3600);
WIRE 3 2175 (-2175 4050)(-2175 3600);
WIRE 3 2175 (-2600 3600)(-2175 3600);
WIRE 16 -1 (-5850 1775)(-3975 1775);
FORCEPROP 0 LAST VOLTAGE 5
J 0
(-4575 1850);
DISPLAY 1.021277 (-4575 1850);
PAINT SKYBLUE (-4575 1850);
DISPLAY INVISIBLE (-4575 1850);
FORCEPROP 2 LAST SIG_NAME VR_PVCCIN_CPU1_PH2_VCIN
J 0
(-5065 1785);
DISPLAY 0.617021 (-5065 1785);
PAINT ORANGE (-5065 1785);
FORCEPROP 2 LASTPROP $XRERR UNIQUE?
J 0
(-5305 1785);
DISPLAY 0.638298 (-5305 1785);
PAINT MONO (-5305 1785);
DISPLAY INVISIBLE (-5305 1785);
WIRE 16 -1 (-5850 1775)(-5850 2000);
WIRE 16 -1 (-5850 1600)(-5850 1775);
WIRE 16 -1 (-5850 2000)(-5725 2000);
WIRE 16 -1 (-2975 1475)(-2400 1475);
FORCEPROP 2 LAST SIG_NAME A_TSENSE_PVCCIN_CPU1
J 0
(-2622 1494);
DISPLAY 0.617021 (-2622 1494);
PAINT ORANGE (-2622 1494);
WIRE 16 -1 (-2975 1475)(-2975 1275);
WIRE 16 -1 (-2400 1475)(-1875 1475);
WIRE 16 -1 (-2400 1325)(-2400 1475);
WIRE 3 2175 (-4425 3600)(-3875 3600);
WIRE 3 2175 (-4425 3600)(-4425 2975);
WIRE 3 2175 (-3875 3600)(-3875 2975);
WIRE 3 2175 (-4425 2975)(-3875 2975);
WIRE 3 2175 (-5225 825)(-4800 825);
WIRE 3 2175 (-5225 1075)(-5225 825);
WIRE 3 2175 (-4800 1075)(-4800 825);
WIRE 3 2175 (-5225 1075)(-4800 1075);
WIRE 16 -1 (-6900 1125)(-3975 1125);
FORCEPROP 2 LAST SIG_NAME VR_PVCCIN_CPU1_PWM2
J 0
(-6913 1135);
DISPLAY 0.617021 (-6913 1135);
PAINT ORANGE (-6913 1135);
WIRE 16 -1 (-5125 1000)(-5875 1000);
FORCEPROP 2 LAST SIG_NAME VR_PVCCIN_CPU1_PH2_BOOT
J 0
(-5890 1010);
DISPLAY 0.617021 (-5890 1010);
PAINT ORANGE (-5890 1010);
FORCEPROP 2 LASTPROP $XRERR UNIQUE?
J 0
(-6130 1010);
DISPLAY 0.638298 (-6130 1010);
PAINT MONO (-6130 1010);
DISPLAY INVISIBLE (-6130 1010);
WIRE 16 -1 (-5875 1000)(-5875 950);
WIRE 16 2175 (-6100 1100)(-5325 1100);
WIRE 16 2175 (-6100 1100)(-6100 625);
WIRE 16 2175 (-5325 1100)(-5325 625);
WIRE 16 2175 (-6100 625)(-5325 625);
WIRE 16 -1 (-5875 750)(-4200 750);
FORCEPROP 0 LAST VOLTAGE 5
J 0
(-5750 825);
DISPLAY 1.021277 (-5750 825);
PAINT SKYBLUE (-5750 825);
DISPLAY INVISIBLE (-5750 825);
FORCEPROP 2 LAST SIG_NAME VR_PVCCIN_CPU1_PH2_PHASE
J 0
(-5840 760);
DISPLAY 0.617021 (-5840 760);
PAINT ORANGE (-5840 760);
FORCEPROP 2 LASTPROP $XRERR UNIQUE?
J 0
(-6080 760);
DISPLAY 0.638298 (-6080 760);
PAINT MONO (-6080 760);
DISPLAY INVISIBLE (-6080 760);
WIRE 16 -1 (-4200 875)(-4200 750);
WIRE 16 -1 (-3975 875)(-4200 875);
WIRE 16 -1 (-4925 1000)(-4200 1000);
FORCEPROP 2 LAST SIG_NAME VR_PVCCIN_CPU1_PH2_BOOT_R
J 0
(-4790 1010);
DISPLAY 0.617021 (-4790 1010);
PAINT ORANGE (-4790 1010);
FORCEPROP 2 LASTPROP $XRERR UNIQUE?
J 0
(-5030 1010);
DISPLAY 0.638298 (-5030 1010);
PAINT MONO (-5030 1010);
DISPLAY INVISIBLE (-5030 1010);
WIRE 16 -1 (-4200 925)(-4200 1000);
WIRE 16 -1 (-3975 925)(-4200 925);
WIRE 16 2175 (-5575 1300)(-4825 1300);
WIRE 16 2175 (-5575 1700)(-5575 1300);
WIRE 16 2175 (-4825 1700)(-4825 1300);
WIRE 16 2175 (-5575 1700)(-4825 1700);
WIRE 16 -1 (-6000 3375)(-4325 3375);
FORCEPROP 0 LAST VOLTAGE 5
J 0
(-5900 3450);
DISPLAY 1.021277 (-5900 3450);
PAINT SKYBLUE (-5900 3450);
DISPLAY INVISIBLE (-5900 3450);
FORCEPROP 2 LAST SIG_NAME VR_PVCCIN_CPU1_PH1_PHASE
J 0
(-5965 3385);
DISPLAY 0.617021 (-5965 3385);
PAINT ORANGE (-5965 3385);
FORCEPROP 2 LASTPROP $XRERR UNIQUE?
J 0
(-6205 3385);
DISPLAY 0.638298 (-6205 3385);
PAINT MONO (-6205 3385);
DISPLAY INVISIBLE (-6205 3385);
WIRE 16 -1 (-4325 3475)(-4325 3375);
WIRE 16 -1 (-3950 3475)(-4325 3475);
WIRE 16 2175 (-6250 3275)(-5375 3275);
WIRE 16 2175 (-6250 3700)(-6250 3275);
WIRE 16 2175 (-5375 3700)(-5375 3275);
WIRE 16 2175 (-6250 3700)(-5375 3700);
WIRE 16 -1 (-6000 3575)(-6000 3650);
WIRE 16 -1 (-6000 3650)(-5250 3650);
FORCEPROP 2 LAST SIG_NAME VR_PVCCIN_CPU1_PH1_BOOT
J 0
(-5965 3660);
DISPLAY 0.617021 (-5965 3660);
PAINT ORANGE (-5965 3660);
FORCEPROP 2 LASTPROP $XRERR UNIQUE?
J 0
(-6205 3660);
DISPLAY 0.638298 (-6205 3660);
PAINT MONO (-6205 3660);
DISPLAY INVISIBLE (-6205 3660);
WIRE 16 -1 (-6725 3725)(-3950 3725);
WIRE 16 2175 (-5650 4275)(-5000 4275);
WIRE 16 2175 (-5650 4275)(-5650 3875);
WIRE 16 2175 (-5000 4275)(-5000 3875);
WIRE 16 2175 (-5650 3875)(-5000 3875);
WIRE 3 2175 (-5350 3475)(-4975 3475);
WIRE 3 2175 (-5350 3700)(-5350 3475);
WIRE 3 2175 (-4975 3700)(-4975 3475);
WIRE 3 2175 (-5350 3700)(-4975 3700);
WIRE 16 -1 (-550 4175)(-550 4125);
WIRE 16 -1 (-550 4175)(-2950 4175);
FORCEPROP 0 LAST SIG_NAME VR_PVCCIN_CPU1_PH1_OCSET
J 0
(-2810 4185);
DISPLAY 0.617021 (-2810 4185);
PAINT ORANGE (-2810 4185);
FORCEPROP 2 LASTPROP $XRERR UNIQUE?
J 0
(-3050 4185);
DISPLAY 0.638298 (-3050 4185);
PAINT MONO (-3050 4185);
DISPLAY INVISIBLE (-3050 4185);
WIRE 16 -1 (-2950 4125)(-2200 4125);
FORCEPROP 0 LAST SIG_NAME NC_PVCCIN_CPU1_PH1_P31
J 0
(-2810 4135);
DISPLAY 0.617021 (-2810 4135);
PAINT ORANGE (-2810 4135);
FORCEPROP 2 LASTPROP $XRERR UNIQUE?
J 0
(-2170 4125);
DISPLAY 0.638298 (-2170 4125);
PAINT MONO (-2170 4125);
DISPLAY INVISIBLE (-2170 4125);
WIRE 16 -1 (-2950 4075)(-2450 4075);
FORCEPROP 2 LAST SIG_NAME A_TSENSE_PVCCIN_CPU1
J 0
(-2813 4085);
DISPLAY 0.617021 (-2813 4085);
PAINT ORANGE (-2813 4085);
WIRE 16 -1 (-2950 4075)(-2950 3875);
WIRE 16 -1 (-2450 4075)(-1925 4075);
WIRE 16 -1 (-2450 3925)(-2450 4075);
WIRE 16 -1 (-2950 3525)(-2400 3525);
FORCEPROP 0 LAST VOLTAGE 5
J 0
(-2525 3600);
DISPLAY 1.021277 (-2525 3600);
PAINT SKYBLUE (-2525 3600);
DISPLAY INVISIBLE (-2525 3600);
FORCEPROP 2 LAST SIG_NAME VR_PVCCIN_CPU1_PHASE1
J 0
(-2790 3535);
DISPLAY 0.617021 (-2790 3535);
PAINT ORANGE (-2790 3535);
FORCEPROP 2 LASTPROP $XRERR UNIQUE?
J 0
(-3030 3535);
DISPLAY 0.638298 (-3030 3535);
PAINT MONO (-3030 3535);
DISPLAY INVISIBLE (-3030 3535);
WIRE 16 -1 (-2400 3525)(-2100 3525);
WIRE 16 -1 (-2400 3450)(-2400 3525);
WIRE 16 -1 (-5050 3650)(-4325 3650);
FORCEPROP 2 LAST SIG_NAME VR_PVCCIN_CPU1_PH1_BOOT_R
J 0
(-4965 3660);
DISPLAY 0.617021 (-4965 3660);
PAINT ORANGE (-4965 3660);
FORCEPROP 2 LASTPROP $XRERR UNIQUE?
J 0
(-5205 3660);
DISPLAY 0.638298 (-5205 3660);
PAINT MONO (-5205 3660);
DISPLAY INVISIBLE (-5205 3660);
WIRE 16 -1 (-4325 3525)(-4325 3650);
WIRE 16 -1 (-3950 3525)(-4325 3525);
WIRE 16 -1 (-1850 4725)(-4175 4725);
FORCEPROP 2 LAST SIG_NAME VR_PVCCIN_CPU1_AIREF1
J 2
(-3503 4760);
DISPLAY 0.617021 (-3503 4760);
PAINT ORANGE (-3503 4760);
WIRE 16 -1 (-4175 3625)(-4175 4725);
WIRE 16 -1 (-3950 3625)(-4175 3625);
WIRE 16 -1 (-4175 3425)(-4175 3625);
WIRE 16 -1 (-3950 3875)(-4825 3875);
FORCEPROP 0 LAST SIG_NAME TP_PVCCINC_CPU1_PH1_GL_1
J 0
(-4810 3885);
DISPLAY 0.617021 (-4810 3885);
PAINT ORANGE (-4810 3885);
FORCEPROP 2 LASTPROP $XRERR UNIQUE?
J 0
(-5065 3875);
DISPLAY 0.638298 (-5065 3875);
PAINT MONO (-5065 3875);
DISPLAY INVISIBLE (-5065 3875);
WIRE 16 -1 (-4800 3825)(-3950 3825);
FORCEPROP 0 LAST SIG_NAME TP_PVCCINC_CPU1_PH1_GL_0
J 0
(-4785 3835);
DISPLAY 0.617021 (-4785 3835);
PAINT ORANGE (-4785 3835);
FORCEPROP 2 LASTPROP $XRERR UNIQUE?
J 0
(-5040 3825);
DISPLAY 0.638298 (-5040 3825);
PAINT MONO (-5040 3825);
DISPLAY INVISIBLE (-5040 3825);
WIRE 16 -1 (-4700 1225)(-3975 1225);
FORCEPROP 0 LAST SIG_NAME TP_PVCCINC_CPU1_PH2_GL_0
J 0
(-4685 1235);
DISPLAY 0.617021 (-4685 1235);
PAINT ORANGE (-4685 1235);
FORCEPROP 2 LASTPROP $XRERR UNIQUE?
J 0
(-4940 1225);
DISPLAY 0.638298 (-4940 1225);
PAINT MONO (-4940 1225);
DISPLAY INVISIBLE (-4940 1225);
WIRE 16 -1 (-5950 4375)(-3950 4375);
FORCEPROP 0 LAST VOLTAGE 5
J 0
(-5350 4450);
DISPLAY 1.021277 (-5350 4450);
PAINT SKYBLUE (-5350 4450);
DISPLAY INVISIBLE (-5350 4450);
FORCEPROP 2 LAST SIG_NAME VR_PVCCIN_CPU1_PH1_VCIN
J 0
(-5865 4385);
DISPLAY 0.617021 (-5865 4385);
PAINT ORANGE (-5865 4385);
FORCEPROP 2 LASTPROP $XRERR UNIQUE?
J 0
(-6105 4385);
DISPLAY 0.638298 (-6105 4385);
PAINT MONO (-6105 4385);
DISPLAY INVISIBLE (-6105 4385);
WIRE 16 -1 (-5950 4375)(-5950 4625);
WIRE 16 -1 (-5950 4175)(-5950 4375);
WIRE 16 -1 (-5950 4625)(-5800 4625);
WIRE 16 -1 (-1825 4375)(-2950 4375);
FORCEPROP 2 LAST SIG_NAME ISENSE_PVCCIN_CPU1_PH1_IMON
J 0
(-2638 4385);
DISPLAY 0.617021 (-2638 4385);
PAINT ORANGE (-2638 4385);
WIRE 16 -1 (-2975 1575)(-1025 1575);
FORCEPROP 0 LAST SIG_NAME VR_PVCCIN_CPU1_PH2_OCSET
J 0
(-2835 1585);
DISPLAY 0.617021 (-2835 1585);
PAINT ORANGE (-2835 1585);
FORCEPROP 2 LASTPROP $XRERR UNIQUE?
J 0
(-3075 1585);
DISPLAY 0.638298 (-3075 1585);
PAINT MONO (-3075 1585);
DISPLAY INVISIBLE (-3075 1585);
WIRE 16 -1 (-1025 1575)(-1025 1500);
WIRE 16 -1 (-2975 1525)(-2225 1525);
FORCEPROP 0 LAST SIG_NAME NC_PVCCIN_CPU1_PH2_P31
J 0
(-2835 1535);
DISPLAY 0.617021 (-2835 1535);
PAINT ORANGE (-2835 1535);
FORCEPROP 2 LASTPROP $XRERR UNIQUE?
J 0
(-2195 1525);
DISPLAY 0.638298 (-2195 1525);
PAINT MONO (-2195 1525);
DISPLAY INVISIBLE (-2195 1525);
WIRE 16 -1 (-3975 1275)(-4725 1275);
FORCEPROP 0 LAST SIG_NAME TP_PVCCINC_CPU1_PH2_GL_1
J 0
(-4710 1285);
DISPLAY 0.617021 (-4710 1285);
PAINT ORANGE (-4710 1285);
FORCEPROP 2 LASTPROP $XRERR UNIQUE?
J 0
(-4965 1275);
DISPLAY 0.638298 (-4965 1275);
PAINT MONO (-4965 1275);
DISPLAY INVISIBLE (-4965 1275);
DOT 1 (-5075 2000);
DOT 1 (-5250 2000);
DOT 1 (-1525 925);
DOT 1 (-2775 775);
DOT 1 (-2775 725);
DOT 1 (-2350 925);
DOT 1 (-2400 1475);
DOT 1 (-2400 3525);
DOT 1 (-4150 1025);
DOT 1 (-6175 1250);
DOT 1 (-2450 4075);
DOT 1 (-7450 1250);
DOT 1 (-7450 1725);
DOT 1 (-7125 1250);
DOT 1 (-6800 1250);
DOT 1 (-7125 1725);
DOT 1 (-6800 1725);
DOT 1 (-6450 1250);
DOT 1 (-6450 1725);
DOT 1 (-6175 1725);
DOT 1 (-7425 3825);
DOT 1 (-7175 3825);
DOT 1 (-6875 3825);
DOT 1 (-6575 3825);
DOT 1 (-6250 3825);
DOT 1 (-5850 1250);
DOT 1 (-5850 1775);
DOT 1 (-5250 1250);
DOT 1 (-5150 2000);
DOT 1 (-4450 1725);
DOT 1 (-4300 1575);
DOT 1 (-5950 3825);
DOT 1 (-5375 3825);
DOT 1 (-7425 4325);
DOT 1 (-7175 4325);
DOT 1 (-6875 4325);
DOT 1 (-6575 4325);
DOT 1 (-6250 4325);
DOT 1 (-5950 4375);
DOT 1 (-5375 4625);
DOT 1 (-5250 4625);
DOT 1 (-4550 4175);
DOT 1 (-4425 4325);
DOT 1 (-4550 4625);
DOT 1 (-2775 675);
DOT 1 (-2725 3325);
DOT 1 (-2725 3275);
DOT 1 (-2725 3375);
DOT 1 (-1075 925);
DOT 1 (-1425 3175);
DOT 1 (-1425 3525);
DOT 1 (-4175 3625);
DOT 1 (-975 3525);
DOT 1 (-1650 3525);
DOT 1 (-1075 550);
DOT 1 (-1825 925);
FORCENOTE
TP FAB1 CO-LAY WITH TI PARTS 11/16
(-2125 1175) 0;
DISPLAY LEFT (-2125 1175);
DISPLAY 0.851064 (-2125 1175);
PAINT RED (-2125 1175);
FORCENOTE
TP FAB1 CO-LAY WITH TI PARTS 11/16
(-5375 3200) 0;
DISPLAY LEFT (-5375 3200);
DISPLAY 0.851064 (-5375 3200);
PAINT RED (-5375 3200);
FORCENOTE
PLACE ON TOP
(-5555 1175) 0;
DISPLAY LEFT (-5555 1175);
DISPLAY 1.553191 (-5555 1175);
PAINT PURPLE (-5555 1175);
FORCENOTE
SPOF
(-6430 1000) 0;
DISPLAY LEFT (-6430 1000);
DISPLAY 1.808511 (-6430 1000);
PAINT PURPLE (-6430 1000);
FORCENOTE
ROOM=PROC_VRD_VCCIN_CPU1
(-8141 318) 0;
DISPLAY LEFT (-8141 318);
DISPLAY 2.510638 (-8141 318);
PAINT PURPLE (-8141 318);
FORCENOTE
SPOF
(-6080 3150) 0;
DISPLAY LEFT (-6080 3150);
DISPLAY 1.936170 (-6080 3150);
PAINT PURPLE (-6080 3150);
FORCENOTE
PLACE ON TOP
(-5605 3775) 0;
DISPLAY LEFT (-5605 3775);
DISPLAY 1.553191 (-5605 3775);
PAINT PURPLE (-5605 3775);
FORCENOTE
TP FAB1 CO-LAY WITH TI PARTS 11/16
(-2150 3825) 0;
DISPLAY LEFT (-2150 3825);
DISPLAY 0.851064 (-2150 3825);
PAINT RED (-2150 3825);
FORCENOTE
TP FAB1 CO-LAY WITH TI PARTS 11/16
(-5350 500) 0;
DISPLAY LEFT (-5350 500);
DISPLAY 0.851064 (-5350 500);
PAINT RED (-5350 500);
FORCENOTE
TP FAB1 3.01 OHM NEED CHANGE TO 2.2 OHM BUT WAIT FOR SYMBOL
(-2125 375) 0;
DISPLAY LEFT (-2125 375);
DISPLAY 0.851064 (-2125 375);
PAINT RED (-2125 375);
FORCENOTE
TP FAB1 CO-LAY WITH TI PARTS 11/16
(-2125 450) 0;
DISPLAY LEFT (-2125 450);
DISPLAY 0.851064 (-2125 450);
PAINT RED (-2125 450);
FORCENOTE
TP FAB1 3.01 OHM NEED CHANGE TO 2.2 OHM BUT WAIT FOR SYMBOL
(-2200 2900) 0;
DISPLAY LEFT (-2200 2900);
DISPLAY 0.851064 (-2200 2900);
PAINT RED (-2200 2900);
FORCENOTE
TP FAB1 CO-LAY WITH TI PARTS 11/16
(-2200 2950) 0;
DISPLAY LEFT (-2200 2950);
DISPLAY 0.851064 (-2200 2950);
PAINT RED (-2200 2950);
QUIT
